G04 ================== begin FILE IDENTIFICATION RECORD ==================*
G04 Layout Name:  DAT6MTH3AD0_t6m_cm_d_brd_103112_274.brd*
G04 Film Name:    gnd3*
G04 File Format:  Gerber RS274X*
G04 File Origin:  Cadence Allegro 16.3-S048*
G04 Origin Date:  Tue Nov 26 10:18:26 2013*
G04 *
G04 Layer:  DRAWING FORMAT/TITLE_DATA_GND3*
G04 Layer:  VIA CLASS/GND3*
G04 Layer:  PIN/GND3*
G04 Layer:  MANUFACTURING/PHOTOPLOT_OUTLINE*
G04 Layer:  ETCH/GND3*
G04 Layer:  DRAWING FORMAT/TITLE_BLOCK*
G04 *
G04 Offset:    (0.00 0.00)*
G04 Mirror:    No*
G04 Mode:      Negative*
G04 Rotation:  0*
G04 FullContactRelief:  No*
G04 UndefLineWidth:     6.00*
G04 ================== end FILE IDENTIFICATION RECORD ====================*
%FSLAX25Y25*MOIN*%
%IR0*IPPOS*OFA0.00000B0.00000*MIA0B0*SFA1.00000B1.00000*%
%ADD10C,.03*%
%ADD17C,.06*%
%ADD46C,.061*%
%AMMACRO37*
4,1,36,0.0,.01,
-.001736,.009848,
-.00342,.009397,
-.005,.00866,
-.006428,.00766,
-.00766,.006428,
-.00866,.005,
-.009397,.00342,
-.009848,.001736,
-.01,0.0,
-.009848,-.001736,
-.009397,-.00342,
-.00866,-.005,
-.00766,-.006428,
-.006428,-.00766,
-.005,-.00866,
-.00342,-.009397,
-.001736,-.009848,
0.0,-.01,
.001736,-.009848,
.00342,-.009397,
.005,-.00866,
.006428,-.00766,
.00766,-.006428,
.00866,-.005,
.009397,-.00342,
.009848,-.001736,
.01,0.0,
.009848,.001736,
.009397,.00342,
.00866,.005,
.00766,.006428,
.006428,.00766,
.005,.00866,
.00342,.009397,
.001736,.009848,
0.0,.01,
0.0*
%
%ADD37MACRO37*%
%ADD34C,.026*%
%ADD21C,.053*%
%ADD11C,.08*%
%ADD36C,.072*%
%AMMACRO53*
4,1,16,.04526,.02758,
.049362,.019302,
.051963,.010437,
.052986,.001255,
.052399,-.007965,
.05022,-.016943,
.046515,-.025406,
.04526,-.02758,
.05033,-.03266,
.055237,-.023424,
.058465,-.013476,
.059917,-.003119,
.059548,.007332,
.057371,.017562,
.053449,.027257,
.05033,.03266,
.04526,.02758,
90.*
4,1,16,.02758,-.04526,
.019302,-.049362,
.010437,-.051963,
.001255,-.052986,
-.007965,-.052399,
-.016943,-.05022,
-.025406,-.046515,
-.02758,-.04526,
-.03266,-.05033,
-.023424,-.055237,
-.013476,-.058465,
-.003119,-.059917,
.007332,-.059548,
.017562,-.057371,
.027257,-.053449,
.03266,-.05033,
.02758,-.04526,
90.*
4,1,16,-.04526,-.02758,
-.049362,-.019302,
-.051963,-.010437,
-.052986,-.001255,
-.052399,.007965,
-.05022,.016943,
-.046515,.025406,
-.04526,.02758,
-.05033,.03266,
-.055237,.023424,
-.058465,.013476,
-.059917,.003119,
-.059548,-.007332,
-.057371,-.017562,
-.053449,-.027257,
-.05033,-.03266,
-.04526,-.02758,
90.*
4,1,16,-.02758,.04526,
-.019302,.049362,
-.010437,.051963,
-.001255,.052986,
.007965,.052399,
.016943,.05022,
.025406,.046515,
.02758,.04526,
.03266,.05033,
.023424,.055237,
.013476,.058465,
.003119,.059917,
-.007332,.059548,
-.017562,.057371,
-.027257,.053449,
-.03266,.05033,
-.02758,.04526,
90.*
%
%ADD53MACRO53*%
%ADD51C,.046*%
%ADD41C,.064*%
%ADD48C,.056*%
%ADD44C,.066*%
%ADD38C,.076*%
%AMMACRO32*
4,1,36,0.0,.004,
.000695,.003939,
.001368,.003759,
.002,.003464,
.002571,.003064,
.003064,.002571,
.003464,.002,
.003759,.001368,
.003939,.000695,
.004,0.0,
.003939,-.000695,
.003759,-.001368,
.003464,-.002,
.003064,-.002571,
.002571,-.003064,
.002,-.003464,
.001368,-.003759,
.000695,-.003939,
0.0,-.004,
-.000695,-.003939,
-.001368,-.003759,
-.002,-.003464,
-.002571,-.003064,
-.003064,-.002571,
-.003464,-.002,
-.003759,-.001368,
-.003939,-.000695,
-.004,0.0,
-.003939,.000695,
-.003759,.001368,
-.003464,.002,
-.003064,.002571,
-.002571,.003064,
-.002,.003464,
-.001368,.003759,
-.000695,.003939,
0.0,.004,
180.*
%
%ADD32MACRO32*%
%AMMACRO26*
4,1,36,0.0,.004,
.000695,.003939,
.001368,.003759,
.002,.003464,
.002571,.003064,
.003064,.002571,
.003464,.002,
.003759,.001368,
.003939,.000695,
.004,0.0,
.003939,-.000695,
.003759,-.001368,
.003464,-.002,
.003064,-.002571,
.002571,-.003064,
.002,-.003464,
.001368,-.003759,
.000695,-.003939,
0.0,-.004,
-.000695,-.003939,
-.001368,-.003759,
-.002,-.003464,
-.002571,-.003064,
-.003064,-.002571,
-.003464,-.002,
-.003759,-.001368,
-.003939,-.000695,
-.004,0.0,
-.003939,.000695,
-.003759,.001368,
-.003464,.002,
-.003064,.002571,
-.002571,.003064,
-.002,.003464,
-.001368,.003759,
-.000695,.003939,
0.0,.004,
270.*
%
%ADD26MACRO26*%
%ADD33C,.095*%
%ADD28C,.068*%
%AMMACRO22*
4,1,20,-.0075,-.07601,
-.01225,-.074283,
-.016628,-.071757,
-.020501,-.06851,
-.023751,-.064639,
-.026279,-.060263,
-.02801,-.055514,
-.028889,-.050536,
-.029,-.048,
-.029,-.0075,
-.022,-.0075,
-.022,-.048,
-.021666,-.05182,
-.020673,-.055523,
-.019053,-.058998,
-.016854,-.062139,
-.014142,-.064851,
-.011002,-.06705,
-.007526,-.06867,
-.0075,-.06868,
-.0075,-.07601,
180.*
4,1,20,.0075,-.07601,
.0075,-.06868,
.010977,-.067064,
.014121,-.064869,
.016836,-.062161,
.019039,-.059023,
.020664,-.05555,
.021661,-.051847,
.022,-.048028,
.022,-.048,
.022,-.0075,
.029,-.0075,
.029,-.048,
.028559,-.053035,
.027251,-.057917,
.025115,-.062498,
.022216,-.066638,
.018642,-.070212,
.014502,-.073111,
.009921,-.075247,
.0075,-.07601,
180.*
4,1,20,-.029,.0075,
-.029,.048,
-.028559,.053035,
-.027251,.057917,
-.025115,.062498,
-.022216,.066638,
-.018642,.070212,
-.014502,.073111,
-.009921,.075247,
-.0075,.07601,
-.0075,.06868,
-.010977,.067064,
-.014121,.064869,
-.016836,.062161,
-.019039,.059023,
-.020664,.05555,
-.021661,.051847,
-.022,.048028,
-.022,.048,
-.022,.0075,
-.029,.0075,
180.*
4,1,20,.022,.0075,
.022,.048,
.021666,.05182,
.020673,.055523,
.019053,.058998,
.016854,.062139,
.014142,.064851,
.011002,.06705,
.007526,.06867,
.0075,.06868,
.0075,.07601,
.01225,.074283,
.016628,.071757,
.020501,.06851,
.023751,.064639,
.026279,.060263,
.02801,.055514,
.028889,.050536,
.029,.048,
.029,.0075,
.022,.0075,
180.*
%
%ADD22MACRO22*%
%ADD19C,.077*%
%ADD23C,.089*%
%AMMACRO52*
4,1,16,.0711,.04282,
.077455,.029823,
.081457,.01592,
.082984,.001533,
.08199,-.0129,
.078504,-.026942,
.072633,-.040164,
.0711,-.04282,
.07619,-.04791,
.083352,-.033952,
.087981,-.018962,
.089937,-.003396,
.089161,.012273,
.085675,.027569,
.079586,.042027,
.07619,.04791,
.0711,.04282,
0.0*
4,1,16,.04282,-.0711,
.029823,-.077455,
.01592,-.081457,
.001533,-.082984,
-.0129,-.08199,
-.026942,-.078504,
-.040164,-.072633,
-.04282,-.0711,
-.04791,-.07619,
-.033952,-.083352,
-.018962,-.087981,
-.003396,-.089937,
.012273,-.089161,
.027569,-.085675,
.042027,-.079586,
.04791,-.07619,
.04282,-.0711,
0.0*
4,1,16,-.0711,-.04282,
-.077455,-.029823,
-.081457,-.01592,
-.082984,-.001533,
-.08199,.0129,
-.078504,.026942,
-.072633,.040164,
-.0711,.04282,
-.07619,.04791,
-.083352,.033952,
-.087981,.018962,
-.089937,.003396,
-.089161,-.012273,
-.085675,-.027569,
-.079586,-.042027,
-.07619,-.04791,
-.0711,-.04282,
0.0*
4,1,16,-.04282,.0711,
-.029823,.077455,
-.01592,.081457,
-.001533,.082984,
.0129,.08199,
.026942,.078504,
.040164,.072633,
.04282,.0711,
.04791,.07619,
.033952,.083352,
.018962,.087981,
.003396,.089937,
-.012273,.089161,
-.027569,.085675,
-.042027,.079586,
-.04791,.07619,
-.04282,.0711,
0.0*
%
%ADD52MACRO52*%
%AMMACRO40*
4,1,19,.08773,.07358,
.099174,.057228,
.107605,.039137,
.112766,.019857,
.114501,-.000026,
.112757,-.019909,
.107587,-.039186,
.099148,-.057273,
.08773,-.07358,
.09269,-.07855,
.104922,-.061261,
.113966,-.042111,
.119547,-.021681,
.121496,-.000593,
.119753,.020514,
.114371,.040997,
.105515,.060234,
.093452,.077642,
.09269,.07855,
.08773,.07358,
0.0*
4,1,19,.07358,-.08773,
.057228,-.099174,
.039137,-.107605,
.019857,-.112766,
-.000026,-.114501,
-.019909,-.112757,
-.039186,-.107587,
-.057273,-.099148,
-.07358,-.08773,
-.07855,-.09269,
-.061261,-.104922,
-.042111,-.113966,
-.021681,-.119547,
-.000593,-.121496,
.020514,-.119753,
.040997,-.114371,
.060234,-.105515,
.077642,-.093452,
.07855,-.09269,
.07358,-.08773,
0.0*
4,1,19,-.08773,-.07358,
-.099174,-.057228,
-.107605,-.039137,
-.112766,-.019857,
-.114501,.000026,
-.112757,.019909,
-.107587,.039186,
-.099148,.057273,
-.08773,.07358,
-.09269,.07855,
-.104922,.061261,
-.113966,.042111,
-.119547,.021681,
-.121496,.000593,
-.119753,-.020514,
-.114371,-.040997,
-.105515,-.060234,
-.093452,-.077642,
-.09269,-.07855,
-.08773,-.07358,
0.0*
4,1,19,-.07358,.08773,
-.057228,.099174,
-.039137,.107605,
-.019857,.112766,
.000026,.114501,
.019909,.112757,
.039186,.107587,
.057273,.099148,
.07358,.08773,
.07855,.09269,
.061261,.104922,
.042111,.113966,
.021681,.119547,
.000593,.121496,
-.020514,.119753,
-.040997,.114371,
-.060234,.105515,
-.077642,.093452,
-.07855,.09269,
-.07358,.08773,
0.0*
%
%ADD40MACRO40*%
%AMMACRO54*
4,1,15,.02438,.01377,
.026401,.009327,
.027619,.004601,
.027999,-.000265,
.027527,-.005123,
.02622,-.009825,
.02438,-.01377,
.02948,-.01887,
.032309,-.013464,
.034156,-.007649,
.034965,-.001602,
.034712,.004494,
.033405,.010454,
.031082,.016095,
.02948,.01887,
.02438,.01377,
90.*
4,1,15,.01377,-.02438,
.009327,-.026401,
.004601,-.027619,
-.000265,-.027999,
-.005123,-.027527,
-.009825,-.02622,
-.01377,-.02438,
-.01887,-.02948,
-.013464,-.032309,
-.007649,-.034156,
-.001602,-.034965,
.004494,-.034712,
.010454,-.033405,
.016095,-.031082,
.01887,-.02948,
.01377,-.02438,
90.*
4,1,15,-.02438,-.01377,
-.026401,-.009327,
-.027619,-.004601,
-.027999,.000265,
-.027527,.005123,
-.02622,.009825,
-.02438,.01377,
-.02948,.01887,
-.032309,.013464,
-.034156,.007649,
-.034965,.001602,
-.034712,-.004494,
-.033405,-.010454,
-.031082,-.016095,
-.02948,-.01887,
-.02438,-.01377,
90.*
4,1,15,-.01377,.02438,
-.009327,.026401,
-.004601,.027619,
.000265,.027999,
.005123,.027527,
.009825,.02622,
.01377,.02438,
.01887,.02948,
.013464,.032309,
.007649,.034156,
.001602,.034965,
-.004494,.034712,
-.010454,.033405,
-.016095,.031082,
-.01887,.02948,
-.01377,.02438,
90.*
%
%ADD54MACRO54*%
%AMMACRO30*
4,1,16,.06818,.0399,
.074073,.027454,
.077715,.014175,
.078996,.000464,
.077876,-.01326,
.07439,-.026582,
.068644,-.039096,
.06818,-.0399,
.07329,-.045,
.079991,-.03159,
.084261,-.01722,
.085971,-.002326,
.085069,.012638,
.081582,.027218,
.075616,.040971,
.07329,.045,
.06818,.0399,
0.0*
4,1,16,.0399,-.06818,
.027454,-.074073,
.014175,-.077715,
.000464,-.078996,
-.01326,-.077876,
-.026582,-.07439,
-.039096,-.068644,
-.0399,-.06818,
-.045,-.07329,
-.03159,-.079991,
-.01722,-.084261,
-.002326,-.085971,
.012638,-.085069,
.027218,-.081582,
.040971,-.075616,
.045,-.07329,
.0399,-.06818,
0.0*
4,1,16,-.06818,-.0399,
-.074073,-.027454,
-.077715,-.014175,
-.078996,-.000464,
-.077876,.01326,
-.07439,.026582,
-.068644,.039096,
-.06818,.0399,
-.07329,.045,
-.079991,.03159,
-.084261,.01722,
-.085971,.002326,
-.085069,-.012638,
-.081582,-.027218,
-.075616,-.040971,
-.07329,-.045,
-.06818,-.0399,
0.0*
4,1,16,-.0399,.06818,
-.027454,.074073,
-.014175,.077715,
-.000464,.078996,
.01326,.077876,
.026582,.07439,
.039096,.068644,
.0399,.06818,
.045,.07329,
.03159,.079991,
.01722,.084261,
.002326,.085971,
-.012638,.085069,
-.027218,.081582,
-.040971,.075616,
-.045,.07329,
-.0399,.06818,
0.0*
%
%ADD30MACRO30*%
%AMMACRO47*
4,1,15,.02291,.0123,
.024698,.008135,
.025735,.003723,
.025991,-.000803,
.025456,-.005304,
.024149,-.009644,
.02291,-.0123,
.02803,-.01742,
.030629,-.012288,
.032298,-.006783,
.032985,-.001071,
.03267,.004673,
.031362,.010275,
.029101,.015565,
.02803,.01742,
.02291,.0123,
90.*
4,1,15,.0123,-.02291,
.008135,-.024698,
.003723,-.025735,
-.000803,-.025991,
-.005304,-.025456,
-.009644,-.024149,
-.0123,-.02291,
-.01742,-.02803,
-.012288,-.030629,
-.006783,-.032298,
-.001071,-.032985,
.004673,-.03267,
.010275,-.031362,
.015565,-.029101,
.01742,-.02803,
.0123,-.02291,
90.*
4,1,15,-.02291,-.0123,
-.024698,-.008135,
-.025735,-.003723,
-.025991,.000803,
-.025456,.005304,
-.024149,.009644,
-.02291,.0123,
-.02803,.01742,
-.030629,.012288,
-.032298,.006783,
-.032985,.001071,
-.03267,-.004673,
-.031362,-.010275,
-.029101,-.015565,
-.02803,-.01742,
-.02291,-.0123,
90.*
4,1,15,-.0123,.02291,
-.008135,.024698,
-.003723,.025735,
.000803,.025991,
.005304,.025456,
.009644,.024149,
.0123,.02291,
.01742,.02803,
.012288,.030629,
.006783,.032298,
.001071,.032985,
-.004673,.03267,
-.010275,.031362,
-.015565,.029101,
-.01742,.02803,
-.0123,.02291,
90.*
%
%ADD47MACRO47*%
%AMMACRO27*
4,1,15,.02438,.01377,
.026401,.009327,
.027619,.004601,
.027999,-.000265,
.027527,-.005123,
.02622,-.009825,
.02438,-.01377,
.02948,-.01887,
.032309,-.013464,
.034156,-.007649,
.034965,-.001602,
.034712,.004494,
.033405,.010454,
.031082,.016095,
.02948,.01887,
.02438,.01377,
0.0*
4,1,15,.01377,-.02438,
.009327,-.026401,
.004601,-.027619,
-.000265,-.027999,
-.005123,-.027527,
-.009825,-.02622,
-.01377,-.02438,
-.01887,-.02948,
-.013464,-.032309,
-.007649,-.034156,
-.001602,-.034965,
.004494,-.034712,
.010454,-.033405,
.016095,-.031082,
.01887,-.02948,
.01377,-.02438,
0.0*
4,1,15,-.02438,-.01377,
-.026401,-.009327,
-.027619,-.004601,
-.027999,.000265,
-.027527,.005123,
-.02622,.009825,
-.02438,.01377,
-.02948,.01887,
-.032309,.013464,
-.034156,.007649,
-.034965,.001602,
-.034712,-.004494,
-.033405,-.010454,
-.031082,-.016095,
-.02948,-.01887,
-.02438,-.01377,
0.0*
4,1,15,-.01377,.02438,
-.009327,.026401,
-.004601,.027619,
.000265,.027999,
.005123,.027527,
.009825,.02622,
.01377,.02438,
.01887,.02948,
.013464,.032309,
.007649,.034156,
.001602,.034965,
-.004494,.034712,
-.010454,.033405,
-.016095,.031082,
-.01887,.02948,
-.01377,.02438,
0.0*
%
%ADD27MACRO27*%
%AMMACRO20*
4,1,15,.0218,.01119,
.023412,.007234,
.024313,.003059,
.024474,-.001209,
.023893,-.005441,
.022585,-.009507,
.0218,-.01119,
.02694,-.01633,
.029366,-.011404,
.030901,-.006131,
.031496,-.000672,
.031134,.004807,
.029826,.010141,
.027612,.015166,
.02694,.01633,
.0218,.01119,
90.*
4,1,15,.01119,-.0218,
.007234,-.023412,
.003059,-.024313,
-.001209,-.024474,
-.005441,-.023893,
-.009507,-.022585,
-.01119,-.0218,
-.01633,-.02694,
-.011404,-.029366,
-.006131,-.030901,
-.000672,-.031496,
.004807,-.031134,
.010141,-.029826,
.015166,-.027612,
.01633,-.02694,
.01119,-.0218,
90.*
4,1,15,-.0218,-.01119,
-.023412,-.007234,
-.024313,-.003059,
-.024474,.001209,
-.023893,.005441,
-.022585,.009507,
-.0218,.01119,
-.02694,.01633,
-.029366,.011404,
-.030901,.006131,
-.031496,.000672,
-.031134,-.004807,
-.029826,-.010141,
-.027612,-.015166,
-.02694,-.01633,
-.0218,-.01119,
90.*
4,1,15,-.01119,.0218,
-.007234,.023412,
-.003059,.024313,
.001209,.024474,
.005441,.023893,
.009507,.022585,
.01119,.0218,
.01633,.02694,
.011404,.029366,
.006131,.030901,
.000672,.031496,
-.004807,.031134,
-.010141,.029826,
-.015166,.027612,
-.01633,.02694,
-.01119,.0218,
90.*
%
%ADD20MACRO20*%
%AMMACRO29*
4,1,16,.0273,.01669,
.029783,.011696,
.031362,.006346,
.031987,.000804,
.031641,-.004763,
.030333,-.010185,
.028104,-.015297,
.0273,-.01669,
.03237,-.02176,
.035657,-.015808,
.03786,-.009377,
.038913,-.00266,
.038784,.004138,
.037476,.01081,
.03503,.017153,
.03237,.02176,
.0273,.01669,
0.0*
4,1,16,.01669,-.0273,
.011696,-.029783,
.006346,-.031362,
.000804,-.031987,
-.004763,-.031641,
-.010185,-.030333,
-.015297,-.028104,
-.01669,-.0273,
-.02176,-.03237,
-.015808,-.035657,
-.009377,-.03786,
-.00266,-.038913,
.004138,-.038784,
.01081,-.037476,
.017153,-.03503,
.02176,-.03237,
.01669,-.0273,
0.0*
4,1,16,-.0273,-.01669,
-.029783,-.011696,
-.031362,-.006346,
-.031987,-.000804,
-.031641,.004763,
-.030333,.010185,
-.028104,.015297,
-.0273,.01669,
-.03237,.02176,
-.035657,.015808,
-.03786,.009377,
-.038913,.00266,
-.038784,-.004138,
-.037476,-.01081,
-.03503,-.017153,
-.03237,-.02176,
-.0273,-.01669,
0.0*
4,1,16,-.01669,.0273,
-.011696,.029783,
-.006346,.031362,
-.000804,.031987,
.004763,.031641,
.010185,.030333,
.015297,.028104,
.01669,.0273,
.02176,.03237,
.015808,.035657,
.009377,.03786,
.00266,.038913,
-.004138,.038784,
-.01081,.037476,
-.017153,.03503,
-.02176,.03237,
-.01669,.0273,
0.0*
%
%ADD29MACRO29*%
%ADD18C,.15*%
%ADD31C,.148*%
%ADD39C,.188*%
%AMMACRO25*
4,1,36,0.0,.004,
.000695,.003939,
.001368,.003759,
.002,.003464,
.002571,.003064,
.003064,.002571,
.003464,.002,
.003759,.001368,
.003939,.000695,
.004,0.0,
.003939,-.000695,
.003759,-.001368,
.003464,-.002,
.003064,-.002571,
.002571,-.003064,
.002,-.003464,
.001368,-.003759,
.000695,-.003939,
0.0,-.004,
-.000695,-.003939,
-.001368,-.003759,
-.002,-.003464,
-.002571,-.003064,
-.003064,-.002571,
-.003464,-.002,
-.003759,-.001368,
-.003939,-.000695,
-.004,0.0,
-.003939,.000695,
-.003759,.001368,
-.003464,.002,
-.003064,.002571,
-.002571,.003064,
-.002,.003464,
-.001368,.003759,
-.000695,.003939,
0.0,.004,
90.*
%
%ADD25MACRO25*%
%AMMACRO14*
4,1,36,0.0,.004,
.000695,.003939,
.001368,.003759,
.002,.003464,
.002571,.003064,
.003064,.002571,
.003464,.002,
.003759,.001368,
.003939,.000695,
.004,0.0,
.003939,-.000695,
.003759,-.001368,
.003464,-.002,
.003064,-.002571,
.002571,-.003064,
.002,-.003464,
.001368,-.003759,
.000695,-.003939,
0.0,-.004,
-.000695,-.003939,
-.001368,-.003759,
-.002,-.003464,
-.002571,-.003064,
-.003064,-.002571,
-.003464,-.002,
-.003759,-.001368,
-.003939,-.000695,
-.004,0.0,
-.003939,.000695,
-.003759,.001368,
-.003464,.002,
-.003064,.002571,
-.002571,.003064,
-.002,.003464,
-.001368,.003759,
-.000695,.003939,
0.0,.004,
0.0*
%
%ADD14MACRO14*%
%AMMACRO35*
4,1,36,0.0,.004,
.000695,.003939,
.001368,.003759,
.002,.003464,
.002571,.003064,
.003064,.002571,
.003464,.002,
.003759,.001368,
.003939,.000695,
.004,0.0,
.003939,-.000695,
.003759,-.001368,
.003464,-.002,
.003064,-.002571,
.002571,-.003064,
.002,-.003464,
.001368,-.003759,
.000695,-.003939,
0.0,-.004,
-.000695,-.003939,
-.001368,-.003759,
-.002,-.003464,
-.002571,-.003064,
-.003064,-.002571,
-.003464,-.002,
-.003759,-.001368,
-.003939,-.000695,
-.004,0.0,
-.003939,.000695,
-.003759,.001368,
-.003464,.002,
-.003064,.002571,
-.002571,.003064,
-.002,.003464,
-.001368,.003759,
-.000695,.003939,
0.0,.004,
.001*
%
%ADD35MACRO35*%
%AMMACRO50*
4,1,13,.01917,.00857,
.020367,.005111,
.020945,.001497,
.020887,-.002163,
.020194,-.005757,
.01917,-.00857,
.02438,-.01377,
.026401,-.009327,
.027619,-.004601,
.027999,.000265,
.027527,.005123,
.02622,.009825,
.02438,.01377,
.01917,.00857,
270.*
4,1,13,.00857,-.01917,
.005111,-.020367,
.001497,-.020945,
-.002163,-.020887,
-.005757,-.020194,
-.00857,-.01917,
-.01377,-.02438,
-.009327,-.026401,
-.004601,-.027619,
.000265,-.027999,
.005123,-.027527,
.009825,-.02622,
.01377,-.02438,
.00857,-.01917,
270.*
4,1,13,-.01917,-.00857,
-.020367,-.005111,
-.020945,-.001497,
-.020887,.002163,
-.020194,.005757,
-.01917,.00857,
-.02438,.01377,
-.026401,.009327,
-.027619,.004601,
-.027999,-.000265,
-.027527,-.005123,
-.02622,-.009825,
-.02438,-.01377,
-.01917,-.00857,
270.*
4,1,13,-.00857,.01917,
-.005111,.020367,
-.001497,.020945,
.002163,.020887,
.005757,.020194,
.00857,.01917,
.01377,.02438,
.009327,.026401,
.004601,.027619,
-.000265,.027999,
-.005123,.027527,
-.009825,.02622,
-.01377,.02438,
-.00857,.01917,
270.*
%
%ADD50MACRO50*%
%AMMACRO42*
4,1,15,.02438,.01377,
.026401,.009327,
.027619,.004601,
.027999,-.000265,
.027527,-.005123,
.02622,-.009825,
.02438,-.01377,
.02948,-.01887,
.032309,-.013464,
.034156,-.007649,
.034965,-.001602,
.034712,.004494,
.033405,.010454,
.031082,.016095,
.02948,.01887,
.02438,.01377,
270.*
4,1,15,.01377,-.02438,
.009327,-.026401,
.004601,-.027619,
-.000265,-.027999,
-.005123,-.027527,
-.009825,-.02622,
-.01377,-.02438,
-.01887,-.02948,
-.013464,-.032309,
-.007649,-.034156,
-.001602,-.034965,
.004494,-.034712,
.010454,-.033405,
.016095,-.031082,
.01887,-.02948,
.01377,-.02438,
270.*
4,1,15,-.02438,-.01377,
-.026401,-.009327,
-.027619,-.004601,
-.027999,.000265,
-.027527,.005123,
-.02622,.009825,
-.02438,.01377,
-.02948,.01887,
-.032309,.013464,
-.034156,.007649,
-.034965,.001602,
-.034712,-.004494,
-.033405,-.010454,
-.031082,-.016095,
-.02948,-.01887,
-.02438,-.01377,
270.*
4,1,15,-.01377,.02438,
-.009327,.026401,
-.004601,.027619,
.000265,.027999,
.005123,.027527,
.009825,.02622,
.01377,.02438,
.01887,.02948,
.013464,.032309,
.007649,.034156,
.001602,.034965,
-.004494,.034712,
-.010454,.033405,
-.016095,.031082,
-.01887,.02948,
-.01377,.02438,
270.*
%
%ADD42MACRO42*%
%AMMACRO16*
4,1,15,.02438,.01377,
.026401,.009327,
.027619,.004601,
.027999,-.000265,
.027527,-.005123,
.02622,-.009825,
.02438,-.01377,
.02948,-.01887,
.032309,-.013464,
.034156,-.007649,
.034965,-.001602,
.034712,.004494,
.033405,.010454,
.031082,.016095,
.02948,.01887,
.02438,.01377,
180.*
4,1,15,.01377,-.02438,
.009327,-.026401,
.004601,-.027619,
-.000265,-.027999,
-.005123,-.027527,
-.009825,-.02622,
-.01377,-.02438,
-.01887,-.02948,
-.013464,-.032309,
-.007649,-.034156,
-.001602,-.034965,
.004494,-.034712,
.010454,-.033405,
.016095,-.031082,
.01887,-.02948,
.01377,-.02438,
180.*
4,1,15,-.02438,-.01377,
-.026401,-.009327,
-.027619,-.004601,
-.027999,.000265,
-.027527,.005123,
-.02622,.009825,
-.02438,.01377,
-.02948,.01887,
-.032309,.013464,
-.034156,.007649,
-.034965,.001602,
-.034712,-.004494,
-.033405,-.010454,
-.031082,-.016095,
-.02948,-.01887,
-.02438,-.01377,
180.*
4,1,15,-.01377,.02438,
-.009327,.026401,
-.004601,.027619,
.000265,.027999,
.005123,.027527,
.009825,.02622,
.01377,.02438,
.01887,.02948,
.013464,.032309,
.007649,.034156,
.001602,.034965,
-.004494,.034712,
-.010454,.033405,
-.016095,.031082,
-.01887,.02948,
-.01377,.02438,
180.*
%
%ADD16MACRO16*%
%AMMACRO45*
4,1,15,.02475,.01414,
.026829,.009627,
.028094,.004822,
.028504,-.000129,
.028049,-.005077,
.026741,-.009871,
.02475,-.01414,
.02984,-.01923,
.032726,-.013756,
.034617,-.007864,
.035457,-.001734,
.03522,.00445,
.033912,.010498,
.031574,.016227,
.02984,.01923,
.02475,.01414,
180.*
4,1,15,.01414,-.02475,
.009627,-.026829,
.004822,-.028094,
-.000129,-.028504,
-.005077,-.028049,
-.009871,-.026741,
-.01414,-.02475,
-.01923,-.02984,
-.013756,-.032726,
-.007864,-.034617,
-.001734,-.035457,
.00445,-.03522,
.010498,-.033912,
.016227,-.031574,
.01923,-.02984,
.01414,-.02475,
180.*
4,1,15,-.02475,-.01414,
-.026829,-.009627,
-.028094,-.004822,
-.028504,.000129,
-.028049,.005077,
-.026741,.009871,
-.02475,.01414,
-.02984,.01923,
-.032726,.013756,
-.034617,.007864,
-.035457,.001734,
-.03522,-.00445,
-.033912,-.010498,
-.031574,-.016227,
-.02984,-.01923,
-.02475,-.01414,
180.*
4,1,15,-.01414,.02475,
-.009627,.026829,
-.004822,.028094,
.000129,.028504,
.005077,.028049,
.009871,.026741,
.01414,.02475,
.01923,.02984,
.013756,.032726,
.007864,.034617,
.001734,.035457,
-.00445,.03522,
-.010498,.033912,
-.016227,.031574,
-.01923,.02984,
-.01414,.02475,
180.*
%
%ADD45MACRO45*%
%AMMACRO43*
4,1,16,.02657,.01597,
.02894,.011114,
.03043,.005919,
.030995,.000545,
.030619,-.004845,
.029313,-.010088,
.027115,-.015025,
.02657,-.01597,
.03164,-.02104,
.034813,-.015226,
.036928,-.00895,
.037921,-.002401,
.037762,.00422,
.036455,.010713,
.034041,.016881,
.03164,.02104,
.02657,.01597,
270.*
4,1,16,.01597,-.02657,
.011114,-.02894,
.005919,-.03043,
.000545,-.030995,
-.004845,-.030619,
-.010088,-.029313,
-.015025,-.027115,
-.01597,-.02657,
-.02104,-.03164,
-.015226,-.034813,
-.00895,-.036928,
-.002401,-.037921,
.00422,-.037762,
.010713,-.036455,
.016881,-.034041,
.02104,-.03164,
.01597,-.02657,
270.*
4,1,16,-.02657,-.01597,
-.02894,-.011114,
-.03043,-.005919,
-.030995,-.000545,
-.030619,.004845,
-.029313,.010088,
-.027115,.015025,
-.02657,.01597,
-.03164,.02104,
-.034813,.015226,
-.036928,.00895,
-.037921,.002401,
-.037762,-.00422,
-.036455,-.010713,
-.034041,-.016881,
-.03164,-.02104,
-.02657,-.01597,
270.*
4,1,16,-.01597,.02657,
-.011114,.02894,
-.005919,.03043,
-.000545,.030995,
.004845,.030619,
.010088,.029313,
.015025,.027115,
.01597,.02657,
.02104,.03164,
.015226,.034813,
.00895,.036928,
.002401,.037921,
-.00422,.037762,
-.010713,.036455,
-.016881,.034041,
-.02104,.03164,
-.01597,.02657,
270.*
%
%ADD43MACRO43*%
%AMMACRO49*
4,1,16,.0302,.01959,
.033143,.014048,
.035079,.00808,
.035949,.001865,
.035727,-.004405,
.034419,-.010542,
.032065,-.016359,
.0302,-.01959,
.03524,-.02464,
.038983,-.018146,
.041542,-.011101,
.042839,-.003719,
.042834,.003777,
.041527,.011157,
.038959,.018199,
.03524,.02464,
.0302,.01959,
270.*
4,1,16,.01959,-.0302,
.014048,-.033143,
.00808,-.035079,
.001865,-.035949,
-.004405,-.035727,
-.010542,-.034419,
-.016359,-.032065,
-.01959,-.0302,
-.02464,-.03524,
-.018146,-.038983,
-.011101,-.041542,
-.003719,-.042839,
.003777,-.042834,
.011157,-.041527,
.018199,-.038959,
.02464,-.03524,
.01959,-.0302,
270.*
4,1,16,-.0302,-.01959,
-.033143,-.014048,
-.035079,-.00808,
-.035949,-.001865,
-.035727,.004405,
-.034419,.010542,
-.032065,.016359,
-.0302,.01959,
-.03524,.02464,
-.038983,.018146,
-.041542,.011101,
-.042839,.003719,
-.042834,-.003777,
-.041527,-.011157,
-.038959,-.018199,
-.03524,-.02464,
-.0302,-.01959,
270.*
4,1,16,-.01959,.0302,
-.014048,.033143,
-.00808,.035079,
-.001865,.035949,
.004405,.035727,
.010542,.034419,
.016359,.032065,
.01959,.0302,
.02464,.03524,
.018146,.038983,
.011101,.041542,
.003719,.042839,
-.003777,.042834,
-.011157,.041527,
-.018199,.038959,
-.02464,.03524,
-.01959,.0302,
270.*
%
%ADD49MACRO49*%
%AMMACRO24*
4,1,17,.03056,.01996,
.033562,.01435,
.035544,.008304,
.036446,.002006,
.03624,-.004353,
.034934,-.01058,
.032566,-.016486,
.03056,-.01996,
.0356,-.025,
.0394,-.018438,
.042004,-.011316,
.043331,-.003851,
.043341,.003732,
.042034,.011201,
.039451,.018331,
.035668,.024903,
.0356,.025,
.03056,.01996,
270.*
4,1,17,.01996,-.03056,
.01435,-.033562,
.008304,-.035544,
.002006,-.036446,
-.004353,-.03624,
-.01058,-.034934,
-.016486,-.032566,
-.01996,-.03056,
-.025,-.0356,
-.018438,-.0394,
-.011316,-.042004,
-.003851,-.043331,
.003732,-.043341,
.011201,-.042034,
.018331,-.039451,
.024903,-.035668,
.025,-.0356,
.01996,-.03056,
270.*
4,1,17,-.03056,-.01996,
-.033562,-.01435,
-.035544,-.008304,
-.036446,-.002006,
-.03624,.004353,
-.034934,.01058,
-.032566,.016486,
-.03056,.01996,
-.0356,.025,
-.0394,.018438,
-.042004,.011316,
-.043331,.003851,
-.043341,-.003732,
-.042034,-.011201,
-.039451,-.018331,
-.035668,-.024903,
-.0356,-.025,
-.03056,-.01996,
270.*
4,1,17,-.01996,.03056,
-.01435,.033562,
-.008304,.035544,
-.002006,.036446,
.004353,.03624,
.01058,.034934,
.016486,.032566,
.01996,.03056,
.025,.0356,
.018438,.0394,
.011316,.042004,
.003851,.043331,
-.003732,.043341,
-.011201,.042034,
-.018331,.039451,
-.024903,.035668,
-.025,.0356,
-.01996,.03056,
270.*
%
%ADD24MACRO24*%
%ADD55C,.006*%
%ADD56C,.07006*%
%ADD60C,.09107*%
%ADD59C,.0971*%
%ADD58C,.07807*%
%ADD57C,.07907*%
%ADD61C,.15206*%
%ADD62C,.15806*%
%ADD63C,.19786*%
G75*
%LPD*%
G75*
G36*
G01X-1043962Y-705877D02*
X2300638D01*
Y2342823D01*
X-1043962D01*
Y-705877D01*
G37*
%LPC*%
G75*
G36*
G01X-69803Y813780D02*
G02X-63929Y819654I5874J0D01*
G01X-10373D01*
G02X-9873Y819154I0J-500D01*
G01Y633398D01*
X-9874D01*
Y2500D01*
G02X-10374Y2000I-500J0D01*
G01X-63929D01*
G02X-69803Y7874I0J5874D01*
G01Y813780D01*
G37*
G36*
G01X25591Y119256D02*
G03X33500Y127165I0J7909D01*
G01Y272835D01*
G03X25591Y280744I-7909J0D01*
G01X5906D01*
G02X2004Y284646I0J3902D01*
G01Y650316D01*
X2000Y650312D01*
Y659188D01*
X2004D01*
Y664173D01*
G02X7874Y670043I5870J0D01*
G01X40787D01*
G03X50665Y679921I0J9878D01*
G01Y798726D01*
G02X51165Y799226I500J0D01*
G01X326472D01*
G02X326972Y798726I0J-500D01*
G01Y792323D01*
G03X338461I5744J0D01*
G01Y798726D01*
G02X338961Y799226I500J0D01*
G01X378047D01*
G02X378547Y798726I0J-500D01*
G01Y741142D01*
G03X408933I15193J0D01*
G01Y798726D01*
G02X409433Y799226I500J0D01*
G01X684740D01*
G02X685240Y798726I0J-500D01*
G01Y792323D01*
G03X696728I5744J0D01*
G01Y798726D01*
G02X697228Y799226I500J0D01*
G01X736315D01*
G02X736815Y798726I0J-500D01*
G01Y679921D01*
G03X746693Y670043I9878J0D01*
G01X779528D01*
G02X785398Y664173I0J-5870D01*
G01Y297835D01*
G02X781496Y293933I-3902J0D01*
G01X780315D01*
G03X772405Y286024I0J-7910D01*
G01Y132480D01*
G03X780315Y124571I7910J1D01*
G01X781496D01*
G02X785398Y120669I0J-3902D01*
G01Y7874D01*
G02X779528Y2004I-5870J0D01*
G01X7874D01*
G02X2004Y7874I0J5870D01*
G01Y115354D01*
G02X5906Y119256I3902J0D01*
G01X25591D01*
G37*
%LPD*%
G75*
G36*
G01X636562Y200784D02*
Y194458D01*
X635625Y193521D01*
X634299D01*
X633362Y194458D01*
Y200784D01*
X634299Y201721D01*
X635625D01*
X636562Y200784D01*
G37*
G36*
G01X615052Y202078D02*
Y192609D01*
X613090Y190647D01*
X610314D01*
X608352Y192609D01*
Y202078D01*
X610314Y204040D01*
X613090D01*
X615052Y202078D01*
G37*
G36*
G01X626400Y185616D02*
Y179290D01*
X625463Y178353D01*
X624137D01*
X623200Y179290D01*
Y185616D01*
X624137Y186553D01*
X625463D01*
X626400Y185616D01*
G37*
G36*
G01X615052Y187078D02*
Y177609D01*
X613090Y175647D01*
X610314D01*
X608352Y177609D01*
Y187078D01*
X610314Y189040D01*
X613090D01*
X615052Y187078D01*
G37*
G36*
G01X612516Y69078D02*
G02X608614Y65176I-3902J0D01*
G02X604612Y69178I0J4002D01*
G02X612516I3952J0D01*
G01Y69078D01*
G37*
G36*
G01X587858D02*
G02X583956Y65176I-3902J0D01*
G02X579954Y69178I0J4002D01*
G02X587858I3952J0D01*
G01Y69078D01*
G37*
G36*
G01X397421Y38554D02*
G02X396249Y35852I-3703J1D01*
G01X395926D01*
G03X395426Y35352I0J-501D01*
G01Y35269D01*
G02X392030Y35258I-1709J3285D01*
G01Y35354D01*
G03X391530Y35854I-500J0D01*
G01X391184D01*
G02X391187Y41256I2534J2700D01*
G01X391532D01*
G03X392032Y41756I0J500D01*
G01Y41851D01*
G02X395426Y41839I1685J-3297D01*
G01Y41756D01*
G03X395926Y41256I500J1D01*
G01X396249D01*
G02X397421Y38554I-2531J-2703D01*
G37*
G36*
G01X358051D02*
G02X356879Y35852I-3703J1D01*
G01X356556D01*
G03X356056Y35352I1J-501D01*
G01Y35269D01*
G02X352660Y35258I-1709J3285D01*
G01Y35354D01*
G03X352160Y35854I-500J0D01*
G01X351814D01*
G02X351817Y41256I2534J2700D01*
G01X352162D01*
G03X352662Y41756I0J500D01*
G01Y41851D01*
G02X356056Y41839I1685J-3297D01*
G01Y41756D01*
G03X356556Y41256I501J1D01*
G01X356879D01*
G02X358051Y38554I-2531J-2703D01*
G37*
G54D56*
X-44872Y125213D03*
Y141213D03*
Y232533D03*
Y248533D03*
Y738493D03*
Y754493D03*
X-26872Y125213D03*
Y141213D03*
Y232533D03*
Y248533D03*
Y738493D03*
Y754493D03*
G54D60*
X43898Y168544D03*
Y231457D03*
G54D59*
X151969Y98622D03*
G54D58*
X414961D03*
G54D57*
X434102Y311875D03*
Y232640D03*
G54D61*
X25455Y303232D03*
Y356832D03*
G54D62*
X102362Y247244D03*
Y349606D03*
X354331Y247244D03*
Y349606D03*
G54D63*
X413386Y377165D03*
G54D10*
X-294532Y1044846D03*
X-281332D03*
X-287932D03*
X-267012Y1044916D03*
X-39858Y731383D03*
X-31858D03*
X4390Y533777D03*
X13170Y372673D03*
X18340Y366452D03*
X13120Y375871D03*
X16010Y369168D03*
X21530Y368991D03*
X14140Y391826D03*
X18210Y386530D03*
X13950Y388616D03*
X13390Y397543D03*
X14240Y394866D03*
X19450Y550297D03*
X20650Y546243D03*
X20350Y555807D03*
X18960Y572061D03*
X17876Y578422D03*
X16200Y566921D03*
X17020Y592934D03*
X13510Y591939D03*
X15850Y610980D03*
X14500Y601957D03*
X11980Y617956D03*
X15349Y614142D03*
X14550Y628297D03*
X13807Y634826D03*
X9300Y631472D03*
X9240Y638699D03*
X11680Y656335D03*
X9260Y658321D03*
X14000Y658369D03*
X14170Y653991D03*
X9360Y653943D03*
X23987Y12977D03*
X36848Y25198D03*
X28408Y26414D03*
X30274Y37714D03*
X36588Y32278D03*
X36567Y73145D03*
X39126Y84631D03*
X34008Y91017D03*
X36567Y107988D03*
X32260Y96899D03*
X38280Y362184D03*
X35750Y364593D03*
X33420Y367309D03*
X23860Y366275D03*
X34140Y540345D03*
X34240Y536966D03*
X33231Y556346D03*
X30672Y551245D03*
X23610Y568111D03*
X28112Y591718D03*
X28270Y602194D03*
X33140Y602232D03*
X28185Y612088D03*
X30744Y617898D03*
X24168Y655750D03*
X37920Y651828D03*
X49890Y30392D03*
X51580Y17595D03*
X42205Y21518D03*
X54800Y25547D03*
X50981Y58681D03*
X46981Y58690D03*
X44010Y55170D03*
X54981Y59420D03*
X49559Y50577D03*
X41685Y73110D03*
X54101Y74252D03*
X51340Y69181D03*
X46570Y73891D03*
X47510Y109421D03*
X40690Y359555D03*
X53340Y393132D03*
X49750Y387305D03*
X51720Y384808D03*
X50840Y395761D03*
X47820Y398827D03*
X51670Y462885D03*
X47590Y463876D03*
X49830Y465496D03*
X47200Y467262D03*
X49590Y469432D03*
X49185Y472713D03*
X53769Y513033D03*
X54988Y518683D03*
X54117Y529098D03*
X49857Y520516D03*
X50630Y529281D03*
X41957Y543321D03*
X50140Y550572D03*
X39540Y538464D03*
X50870Y564008D03*
X43467Y555938D03*
X53988Y568748D03*
X49680Y579709D03*
X49620Y574212D03*
X47557Y588971D03*
X44507Y594082D03*
X40908Y589691D03*
X39360Y604593D03*
X39370Y600956D03*
X42950Y612487D03*
X50270Y627793D03*
X48540Y624953D03*
X52230Y614907D03*
X51051Y619407D03*
X48060Y621229D03*
X47480Y616848D03*
X51038Y643928D03*
X46890Y633564D03*
X53751Y652029D03*
X44640Y651029D03*
X40980Y656396D03*
X49720Y668412D03*
X56610Y20553D03*
X60318Y65593D03*
X64190Y72841D03*
X61760Y107321D03*
X55230Y112521D03*
X63900Y112081D03*
X64309Y141882D03*
X67853Y180744D03*
X68690Y175589D03*
X68930Y197193D03*
X66570Y189983D03*
X68830Y215817D03*
X56287Y242872D03*
X63718Y239030D03*
X61945Y267579D03*
X66818Y297483D03*
X57994Y287655D03*
X58000Y412641D03*
X64568Y451029D03*
X67568D03*
X70568D03*
X61357Y483392D03*
Y480892D03*
Y477892D03*
X61188Y487117D03*
X56330Y497940D03*
X58830D03*
X61676Y502656D03*
Y500156D03*
X61188Y489617D03*
Y492117D03*
X55982Y494543D03*
X64480Y501596D03*
X62253Y522589D03*
X67369Y522993D03*
X70696Y527237D03*
X57710Y572918D03*
X57070Y580074D03*
X57440Y585607D03*
X68630Y599945D03*
X61205Y623870D03*
X63570Y613914D03*
X63610Y618917D03*
X61205Y628870D03*
X62160Y644091D03*
X59390Y642906D03*
X56240Y630081D03*
X59530Y631704D03*
X63650Y646957D03*
X61600Y653611D03*
X66880Y761625D03*
X59260Y779815D03*
X58840Y783097D03*
X62290Y779629D03*
X67660Y779452D03*
X62730Y782694D03*
X66860Y782716D03*
X60370Y776861D03*
X64790Y776777D03*
X56500Y789667D03*
X76880Y126528D03*
X76030Y156152D03*
X85010Y171679D03*
X71510Y164548D03*
X74470Y175666D03*
X82553Y185431D03*
X86172Y213852D03*
X75560Y218513D03*
X73870Y205758D03*
X83390Y235665D03*
X79142Y237920D03*
X86479Y249259D03*
X77239Y260814D03*
X81165Y257717D03*
X78373Y276029D03*
X78220Y281745D03*
X78207Y279092D03*
X72190Y297395D03*
X82560Y288099D03*
X82600Y285426D03*
X77368Y299206D03*
X74058Y389621D03*
X83084D03*
X73868Y397913D03*
X83245D03*
X80490Y420690D03*
Y423690D03*
X86050Y428718D03*
X80490Y426690D03*
X79900Y439193D03*
X86050Y425112D03*
Y437470D03*
Y434470D03*
X79900Y445193D03*
Y442193D03*
X85617Y451275D03*
X82617D03*
X86050Y443432D03*
Y446432D03*
X74291Y486665D03*
X83536Y498308D03*
X81174Y503587D03*
X85346Y512295D03*
X73057Y515286D03*
X72635Y508991D03*
X81635Y521104D03*
X82031Y523928D03*
X84990Y563286D03*
X82140Y560758D03*
X81980Y556851D03*
X81516Y577905D03*
X83030Y582656D03*
X85140Y585213D03*
X75380Y608914D03*
Y603914D03*
X102257Y167955D03*
X90905Y199733D03*
X101449Y194368D03*
X98700Y234650D03*
X96990Y223043D03*
X101020Y223348D03*
X88399Y244041D03*
X95951Y376661D03*
X90031Y421693D03*
X90238Y418623D03*
X88617Y451275D03*
X86695Y498180D03*
X87721Y505817D03*
X92422Y531081D03*
X95660Y531362D03*
X98803Y531597D03*
X97268Y537055D03*
X97366Y542897D03*
X88200Y568111D03*
X98370Y619252D03*
X94070Y618986D03*
Y613841D03*
X97790Y613797D03*
X96200Y616325D03*
X95350Y644088D03*
X95310Y647481D03*
X98480Y646217D03*
X98410Y648878D03*
X89810Y765905D03*
X97390Y766435D03*
X98590Y782494D03*
X97180Y786472D03*
X111220Y160923D03*
X106090Y167615D03*
X112530Y186363D03*
X106760Y175370D03*
X114920Y179082D03*
X108910Y193194D03*
X104550Y262359D03*
X104270Y265662D03*
X110230Y360735D03*
X103151Y373340D03*
X110230Y363235D03*
X117030Y389978D03*
X103750Y402740D03*
X103810Y405876D03*
X103870Y399604D03*
X108235Y401017D03*
X111120Y401084D03*
X115727Y405844D03*
X113412Y404826D03*
X113504Y407673D03*
X107531Y394023D03*
X115516Y485696D03*
X117026Y488316D03*
X108026Y492500D03*
X109972Y509321D03*
Y519508D03*
X106358Y785790D03*
X102421Y782191D03*
X110295Y785734D03*
Y782191D03*
X116370Y785941D03*
X104300Y773100D03*
X106650Y779581D03*
X102421Y785938D03*
X130195Y19162D03*
X131068Y76588D03*
X126220Y80364D03*
Y83291D03*
X125480Y91163D03*
X132400Y88153D03*
X129580Y86837D03*
X129780Y92580D03*
X124150Y94643D03*
X128330Y98360D03*
X129650Y250414D03*
Y255414D03*
X130324Y272096D03*
Y277096D03*
X123960Y283696D03*
X128960D03*
X125050Y384546D03*
X122120Y386736D03*
X126300Y390369D03*
X129028Y425593D03*
X126377Y466738D03*
X126260Y470267D03*
X127705Y489431D03*
X125105D03*
X119326Y489706D03*
X121968Y488481D03*
X118124Y510811D03*
X133138Y510114D03*
X121644Y509398D03*
X130596Y510042D03*
X124652Y509398D03*
X130703Y512549D03*
X130844Y515128D03*
X128087Y513874D03*
X124279Y523691D03*
X120300Y572512D03*
X133590Y588438D03*
X130790Y595613D03*
X132190Y662616D03*
X121070Y670509D03*
X132050Y671817D03*
X133607Y686699D03*
X130260Y679836D03*
X132438Y704733D03*
X133490Y695470D03*
X126220Y720949D03*
X132334Y732982D03*
X119900Y754021D03*
X125600Y759000D03*
X125960Y785699D03*
X120090Y780618D03*
X130850Y782456D03*
X118169Y783857D03*
X130660Y785601D03*
X127290Y781982D03*
X122720Y785051D03*
X141490Y19267D03*
X137872Y29551D03*
X147427Y30367D03*
X146380Y20345D03*
X139931Y40842D03*
X139932Y35310D03*
X135050Y53493D03*
X137540Y58255D03*
X143857Y51943D03*
X149025Y51720D03*
X135290Y87664D03*
X140350Y81347D03*
X144400Y244061D03*
Y247561D03*
X148330Y258806D03*
X145200Y276468D03*
X138930Y278965D03*
X148350Y281769D03*
X134540Y267786D03*
X137990Y296735D03*
X139950Y293835D03*
X149020Y303498D03*
X145720Y311336D03*
X146100Y323543D03*
X145580Y316836D03*
X137889Y403348D03*
X141800Y404481D03*
X141847Y401820D03*
X135088Y405060D03*
X135181Y402121D03*
X145295Y404388D03*
X145284Y401507D03*
X142239Y422346D03*
X139395Y425090D03*
X138437Y435930D03*
Y438430D03*
X147576Y445279D03*
Y447779D03*
Y450279D03*
X138437Y440930D03*
X135300Y468444D03*
X146240Y472111D03*
X139310Y478102D03*
X136470Y481994D03*
X149477Y532733D03*
X144120Y547577D03*
X146920Y547677D03*
X143252Y573105D03*
X145550Y588088D03*
X149050Y588044D03*
X141260Y588175D03*
X136420Y599352D03*
X148140Y660112D03*
X148487Y676041D03*
X148200Y669205D03*
X140110Y675907D03*
X139158Y686725D03*
X135280Y679212D03*
X138726Y696707D03*
X138198Y712628D03*
X144631Y735955D03*
X147290Y744113D03*
X145040Y740741D03*
X139600Y781281D03*
X135470Y781697D03*
X135610Y784521D03*
X139680Y784596D03*
X149450Y780429D03*
X146150Y783820D03*
X145570Y780580D03*
X157877Y30674D03*
X152810Y29921D03*
X158165Y21300D03*
X150592Y20974D03*
X156255Y45743D03*
X159861Y36134D03*
X160731Y41038D03*
X162350Y42984D03*
X157659Y47891D03*
X157010Y58963D03*
X164550Y61239D03*
X156440Y74863D03*
X151618Y83343D03*
X164280Y101810D03*
X164490Y127110D03*
X159190Y127781D03*
X152990Y248096D03*
X157690Y249918D03*
X154546Y256986D03*
X152634Y276809D03*
X149721Y292987D03*
X152733Y288517D03*
X158076Y290635D03*
X154581Y308767D03*
X151230Y330164D03*
X150918Y318134D03*
X150510Y336306D03*
X156448Y336629D03*
X162071Y336947D03*
X165290Y385948D03*
X151820Y385554D03*
X150902Y379714D03*
X160886Y380294D03*
X160710Y384044D03*
X162940Y406188D03*
X154370Y449930D03*
X151145Y469456D03*
X150547Y459363D03*
X163377Y484538D03*
X152554Y494027D03*
X158406Y500016D03*
X162335Y512456D03*
X159196Y515612D03*
X159179Y521893D03*
X154126Y524411D03*
X154475Y530422D03*
X159180Y528227D03*
X162335Y543954D03*
X159185Y537654D03*
X162336Y550253D03*
X164259Y557273D03*
X154140Y577815D03*
X161280Y581585D03*
X162786Y568599D03*
X156480Y583315D03*
X153527Y597138D03*
X160699Y587904D03*
X150380Y602885D03*
X153712Y610917D03*
X153330Y599935D03*
X153422Y603043D03*
X153955Y620760D03*
X157963Y633735D03*
X162668Y631897D03*
X162530Y643235D03*
Y636435D03*
X151915Y675068D03*
X155957Y674813D03*
X160112Y674990D03*
X165012Y675887D03*
X164812Y662579D03*
X151567Y687579D03*
X155650Y681515D03*
X161994Y678445D03*
X159590Y683050D03*
X157287Y678138D03*
X165167Y681311D03*
X152222Y678394D03*
X160101Y687962D03*
X163018Y684381D03*
X164092Y688014D03*
X150840Y682436D03*
X154970Y736966D03*
X161981Y730784D03*
X158881D03*
X162640Y743927D03*
X158970D03*
X154400Y744337D03*
X155230Y740259D03*
X163138Y778565D03*
X160480Y777583D03*
X155170Y780656D03*
X164630Y781222D03*
X153320Y783499D03*
X160320Y786346D03*
X149810Y783858D03*
X168961Y27073D03*
X165959Y27133D03*
X173110Y26877D03*
X180907Y27544D03*
X176090Y26906D03*
X180159Y40661D03*
X165336Y46126D03*
X168040Y61462D03*
X177733Y91967D03*
X167383Y93147D03*
X168850Y99251D03*
X169510Y106579D03*
X173900Y97662D03*
X177680Y101764D03*
X174710Y105699D03*
X177763Y121057D03*
X168170Y123367D03*
X173170D03*
X178040Y228978D03*
X167483Y239914D03*
X177891Y249324D03*
X175756Y257668D03*
X173263Y262589D03*
X176301Y262624D03*
X167322Y255855D03*
X167698Y260617D03*
X178929Y262244D03*
X175110Y260412D03*
X178025Y279018D03*
X174078Y271435D03*
X170829Y271452D03*
X178941Y270160D03*
X178810Y287263D03*
X174148Y289289D03*
X175921Y301920D03*
X178921D03*
X178660Y388418D03*
X171934Y386364D03*
X175155Y380727D03*
X180430Y392969D03*
X175663Y386424D03*
X176371Y404721D03*
X180440Y398056D03*
X172760Y406540D03*
X167527Y420268D03*
X179562Y424001D03*
X173381Y424005D03*
X170683Y436834D03*
X170361Y428595D03*
X177525Y451946D03*
X180125D03*
X178961Y448138D03*
X176220Y448247D03*
X171616Y467804D03*
X168370Y477790D03*
X169728Y487664D03*
X168189Y514331D03*
X178085Y512456D03*
X173252Y515693D03*
X165707Y506156D03*
X172087Y510536D03*
X169615Y519216D03*
X178094Y531365D03*
X166297Y532416D03*
X169491Y529702D03*
X166837Y523486D03*
X174395Y527975D03*
X171606Y527511D03*
X168243Y542706D03*
X174930Y547106D03*
X169157Y548676D03*
X173163Y551903D03*
X169444Y558757D03*
X167105Y552882D03*
X178083Y553402D03*
X172889Y562710D03*
X175330Y578535D03*
X166930Y578435D03*
X166786Y569056D03*
X175386Y569589D03*
X179740Y568951D03*
X172430Y584035D03*
X177830Y583535D03*
X166570Y583874D03*
X166605Y587860D03*
X178416Y587849D03*
X179120Y639615D03*
X169930Y635329D03*
X172510Y639771D03*
X167530Y631935D03*
X174479Y631986D03*
X167810Y668131D03*
X168645Y688064D03*
X165628Y691289D03*
X167315Y684943D03*
X178982Y688631D03*
X171180Y683815D03*
X169268Y705304D03*
X169396Y701006D03*
X169268Y697399D03*
X169619Y693335D03*
X180820Y717914D03*
X171154Y715673D03*
X169531Y710542D03*
X175463Y720245D03*
X165599Y730476D03*
X174954Y728404D03*
X177920Y739302D03*
X167568Y743335D03*
X177224Y777765D03*
X169350Y785470D03*
X172600Y780150D03*
X169860Y782086D03*
X167350Y778074D03*
X194825Y10196D03*
X194861Y12952D03*
X183407Y27544D03*
X188634Y27860D03*
X191596Y27620D03*
X184928Y91847D03*
X189928D03*
X196653Y91837D03*
X196493Y105637D03*
X183013Y98813D03*
X190100Y99701D03*
X188203Y104567D03*
X194463Y122631D03*
X184050Y230139D03*
X183550Y235060D03*
X188899Y240208D03*
X195126Y249955D03*
X184296Y241098D03*
X188899Y236808D03*
X181176Y257643D03*
X188658Y256870D03*
X184117Y264852D03*
X181602Y262656D03*
X186873Y263697D03*
X185798Y256760D03*
X186873Y260697D03*
X194693Y259197D03*
Y262197D03*
X188418Y278887D03*
X183440Y269816D03*
X194205Y271034D03*
X191860Y270148D03*
X183198Y278034D03*
X191054Y294424D03*
X183254Y295023D03*
X192298Y286183D03*
X181921Y301920D03*
X191949Y301987D03*
X188810Y301998D03*
X187907Y308784D03*
X186254Y310663D03*
X183254D03*
X186350Y317116D03*
X196476Y317042D03*
X183228Y317023D03*
X193957Y317064D03*
X191159Y317171D03*
X190557Y325701D03*
X192230Y337322D03*
X192040Y333606D03*
X195420Y372406D03*
X184927Y383876D03*
X192681Y377554D03*
X193590Y383383D03*
X185074Y380726D03*
X196273Y403152D03*
X182132Y418327D03*
X192527Y429049D03*
X189077Y438281D03*
X184523Y441915D03*
X181923Y445044D03*
Y442544D03*
X193500Y489796D03*
X181231Y512455D03*
X184843Y533995D03*
X188640Y530667D03*
X191457Y531553D03*
X193466Y546886D03*
X186841Y545372D03*
X181232Y553402D03*
X181491Y557436D03*
X193080Y581235D03*
X191500Y571956D03*
X182480Y566819D03*
X196740Y589735D03*
X181330Y587535D03*
X192130Y632235D03*
X184748Y639687D03*
X182480Y634585D03*
X191480Y639135D03*
X182353Y631612D03*
X196410Y650155D03*
X187410Y649715D03*
Y659705D03*
X191910Y650055D03*
X185993Y682670D03*
X191542Y691925D03*
X181744Y694829D03*
X181950Y698191D03*
X190375Y695624D03*
X188566Y722353D03*
X183566D03*
X193566Y722333D03*
X196079Y723943D03*
X191150Y724108D03*
X186164Y724134D03*
X192949Y771020D03*
X182500Y780786D03*
X189770Y778082D03*
X204785Y13762D03*
X204978Y10605D03*
X201849Y15292D03*
X198577Y15374D03*
X204003Y91247D03*
X200480Y97687D03*
X212423Y104957D03*
X208908Y96975D03*
X205903Y101477D03*
X199993Y103637D03*
X210623Y121267D03*
X205535Y234497D03*
Y228682D03*
X211935Y230585D03*
X198296Y232699D03*
X211935Y237385D03*
Y240785D03*
X205566Y243497D03*
X205271Y240209D03*
X198685Y237385D03*
Y244085D03*
X210305Y259330D03*
Y262289D03*
X201994Y261248D03*
X200977Y256305D03*
X202402Y263713D03*
X200469Y259139D03*
X201518Y265990D03*
X209449Y281098D03*
X210303Y268227D03*
X206299Y281098D03*
X210303Y271227D03*
X203149Y281098D03*
X201518Y268887D03*
X209449Y287398D03*
Y290548D03*
X203149Y287398D03*
X206299D03*
X196867Y294342D03*
X206299Y290548D03*
X206319Y296863D03*
X203149Y290548D03*
X206299Y293698D03*
X198880Y310245D03*
X196812Y308619D03*
X206299Y306298D03*
Y303148D03*
X209449Y312598D03*
X203166Y312577D03*
X202525Y299358D03*
X206299Y315748D03*
X203058Y315593D03*
X200211Y321446D03*
X200572Y323920D03*
X208000Y325200D03*
X208700Y328000D03*
X200590Y327615D03*
X197938Y376839D03*
X206973Y361900D03*
X205790Y387003D03*
X201267Y403294D03*
X210880Y402359D03*
X206380Y402201D03*
X204584Y462478D03*
X197161Y465628D03*
X200459Y487253D03*
X211609Y516553D03*
X205257Y528822D03*
X211287Y528547D03*
X212342Y536729D03*
X199539Y537112D03*
X204309Y539953D03*
X205286Y551130D03*
X202486D03*
X211240Y572893D03*
X210040Y576893D03*
X201510Y576885D03*
X197730Y572893D03*
X197709Y567464D03*
X209590Y580893D03*
X210790Y566926D03*
X209940Y584893D03*
X197230Y595335D03*
X198890Y584105D03*
X207178Y591595D03*
X196907Y605012D03*
X197030Y598535D03*
X204024Y604135D03*
Y609135D03*
X208904Y611515D03*
X200380Y629085D03*
X199786Y618893D03*
X202510Y624005D03*
X197230Y615435D03*
X197130Y626135D03*
X208904Y616515D03*
X197480Y639815D03*
X203065Y638700D03*
X205221Y630886D03*
X200910Y659735D03*
Y650155D03*
X205410Y650035D03*
X199510Y663158D03*
X205410Y661200D03*
X211560Y670575D03*
X202518Y673273D03*
X197889Y671226D03*
X210824Y692266D03*
X199590Y682868D03*
X197582Y703474D03*
X200692Y704081D03*
X199350Y692724D03*
X211236Y695586D03*
X197243Y697899D03*
X198566Y722353D03*
X209017Y722344D03*
X203611Y722303D03*
X205440Y712510D03*
X211897Y723870D03*
X201411Y708231D03*
X205883Y724373D03*
X200817Y724180D03*
X199760Y763929D03*
X202050Y784919D03*
X206210Y771577D03*
X212350Y773283D03*
X222290Y45504D03*
X226290D03*
X221310Y51103D03*
X225310D03*
X215773Y90147D03*
X222983Y91587D03*
X220200Y93561D03*
X226620Y89385D03*
X214320Y101978D03*
X220983Y106174D03*
X213908Y96975D03*
X219510Y101338D03*
X228138Y125802D03*
X226010Y233542D03*
X217135Y230585D03*
X226010Y240342D03*
X217135Y240785D03*
Y237385D03*
X227517Y244187D03*
X216512Y258490D03*
X225973Y262197D03*
X216109Y265139D03*
Y262139D03*
X218508Y256664D03*
X225973Y265197D03*
Y259197D03*
X218899Y281098D03*
X224357Y273228D03*
X216109Y271139D03*
X215749Y281098D03*
X213138Y274187D03*
X225160Y293676D03*
X225199Y290548D03*
Y284248D03*
X222049Y287398D03*
X212599D03*
X215749Y290548D03*
Y293698D03*
Y287398D03*
X225199Y306298D03*
Y312598D03*
X222049Y306298D03*
X218899D03*
X222049Y299998D03*
X212610Y306305D03*
X218899Y299998D03*
Y303148D03*
X218947Y312617D03*
X224949Y328707D03*
X225199Y315748D03*
X224585Y322992D03*
X224711Y325922D03*
X223166Y338842D03*
X222911Y333155D03*
X224996Y334617D03*
X223095Y336241D03*
X221280Y340579D03*
X222974Y356134D03*
X214657Y356205D03*
X214007Y362701D03*
X222225Y364031D03*
X227745Y368007D03*
X224108Y388029D03*
X214786Y388603D03*
X218090Y390891D03*
X216633Y384989D03*
X215120Y399654D03*
X214406Y395539D03*
X223085Y401702D03*
X213710Y402237D03*
X224730Y418003D03*
X221406Y436560D03*
X227816Y442675D03*
X218483Y442550D03*
X221858Y442300D03*
X225024Y442467D03*
X228242Y463681D03*
X223953Y463550D03*
X212809Y479053D03*
X215409Y479253D03*
X222419Y479933D03*
X218040Y473853D03*
X223786Y476638D03*
X226255Y472579D03*
X219309Y489353D03*
X222209D03*
X227284Y502591D03*
X224209Y491853D03*
X217609Y516353D03*
X219328Y528823D03*
X223376Y523322D03*
X215946Y544202D03*
X218950Y565589D03*
X227100Y580916D03*
X225100Y597453D03*
X219960Y596373D03*
Y601373D03*
X215604Y621977D03*
X228290Y629893D03*
X218308Y635939D03*
X225179Y642614D03*
X218240Y674433D03*
X225237Y671772D03*
X212635Y665604D03*
X224060Y690317D03*
X224336Y687758D03*
X223707Y695436D03*
X220580Y692876D03*
X223741Y700554D03*
X221340Y697995D03*
X217530Y715305D03*
X221320Y720698D03*
X213310Y719064D03*
X222710Y713706D03*
X216820Y723301D03*
X227650Y720791D03*
X224410Y719970D03*
X225940Y733671D03*
Y736437D03*
X218270Y785657D03*
X220960Y778561D03*
X226670Y773299D03*
X242290Y45504D03*
X230290D03*
X229310Y51103D03*
X233290Y51045D03*
X237310Y50983D03*
X241310D03*
X235113Y91307D03*
X231013Y91547D03*
X243373Y88767D03*
X239563Y92077D03*
X230643Y108497D03*
X234243Y100156D03*
X233083Y94817D03*
X237773Y103607D03*
X242913Y106157D03*
X233138Y125802D03*
X230749Y160807D03*
X230650Y164566D03*
X230890Y169424D03*
X231000Y173381D03*
X230100Y187389D03*
X230140Y197240D03*
X232948Y234047D03*
X236710Y244042D03*
X242460Y237591D03*
X237654Y249719D03*
X231710Y243642D03*
Y240242D03*
X241613Y262197D03*
X239569Y266639D03*
X241613Y259197D03*
X237594Y252754D03*
X241613Y265197D03*
X233793Y266697D03*
Y257697D03*
X233904Y252772D03*
X239569Y263639D03*
X233793Y263697D03*
X231749Y262139D03*
X233793Y260697D03*
X239569Y260639D03*
X231749Y259139D03*
X234649Y281098D03*
X237865Y281131D03*
X239569Y269639D03*
X232118Y271587D03*
X241613Y271197D03*
Y268197D03*
X228821Y274197D03*
X231648Y274243D03*
X231450Y290583D03*
X237760Y293692D03*
X237799Y287398D03*
X240949Y290548D03*
Y287398D03*
X231499Y284248D03*
Y296848D03*
Y293698D03*
X240949Y296848D03*
X231499Y299998D03*
X237799Y312598D03*
X231499D03*
X240949Y309448D03*
X237799Y303148D03*
X234649D03*
X237799Y306298D03*
X240925Y306257D03*
X240949Y299998D03*
Y303148D03*
X231567Y321742D03*
X232782Y327096D03*
X230725Y325649D03*
X238545Y327149D03*
X240374Y328960D03*
X240511Y325517D03*
X238548Y333149D03*
X230725Y334547D03*
X240598Y334642D03*
X240218Y338010D03*
X231144Y338225D03*
X238560Y336136D03*
X232769Y333207D03*
X232804Y336181D03*
X239290Y340428D03*
X228419Y356855D03*
X233635Y357082D03*
X230010Y373300D03*
X237578Y369584D03*
X233136Y367070D03*
X243078Y368384D03*
X231257Y362218D03*
X228729Y385227D03*
X241451Y392147D03*
X236412Y387722D03*
X231223Y391424D03*
X239546Y390528D03*
X239228Y393291D03*
X236430Y393470D03*
X232647Y396011D03*
X228906Y424560D03*
X228713Y416525D03*
Y419525D03*
X231870Y439511D03*
X228906Y433560D03*
Y427560D03*
Y436560D03*
X231885Y442252D03*
X235319Y464362D03*
X231461Y462591D03*
X243471Y460292D03*
X238430Y460338D03*
X233309Y472553D03*
X237609Y472453D03*
X241909Y472553D03*
X234209Y480953D03*
X228604Y479682D03*
X233626Y512040D03*
X236776Y534087D03*
X233626Y524639D03*
X236776Y540386D03*
X235307Y566357D03*
X243209Y574018D03*
X229269Y597682D03*
X242830Y597415D03*
X234370Y593242D03*
X242796Y589749D03*
X236780Y628738D03*
X229199Y642180D03*
X243693Y632254D03*
X238420Y642148D03*
X234500Y637685D03*
X243743Y636514D03*
X241670Y652558D03*
X233584Y652519D03*
X239168Y671672D03*
X237275Y679609D03*
X239084Y696252D03*
X233954Y697395D03*
X236120Y704173D03*
X242680Y712337D03*
X234960Y714064D03*
X239210Y720040D03*
X234910Y720816D03*
X234940Y733355D03*
X243940Y736412D03*
X239500Y733523D03*
X230440Y724242D03*
X234940Y736392D03*
X236180Y786517D03*
X242230Y774803D03*
X234011Y772902D03*
X250290Y45504D03*
X246290D03*
X258103Y53688D03*
X257500Y56117D03*
X245310Y50867D03*
X249300Y50862D03*
X253490Y53736D03*
X252683Y105867D03*
X253558Y95038D03*
X256133Y99347D03*
X248558Y95038D03*
X249453Y114307D03*
X255287Y226709D03*
X254221Y230582D03*
X256492Y222466D03*
X254181Y234521D03*
X257950Y236924D03*
X254418Y240407D03*
X247389Y259139D03*
X256553Y256881D03*
X249433Y263697D03*
Y260697D03*
X256916Y262609D03*
X247389Y262139D03*
X257253Y259197D03*
X259518Y252358D03*
X249433Y257697D03*
X246467Y255442D03*
X244099Y281098D03*
X254234Y281622D03*
X250399Y281098D03*
X247389Y268139D03*
X257253Y271197D03*
Y268197D03*
X244110Y290505D03*
X257447Y287117D03*
X244099Y287398D03*
X250399D03*
X253549Y290548D03*
X247249Y296848D03*
X244099D03*
X258380Y295984D03*
X254007Y306819D03*
X244118Y303187D03*
X257057Y309636D03*
X244099Y299998D03*
X247249Y306298D03*
X257418Y303533D03*
X258590Y311560D03*
X247290Y327694D03*
X254631Y324716D03*
X254998Y329779D03*
X256276Y322652D03*
X247789Y322910D03*
X254905Y327213D03*
X250401Y315713D03*
X253710Y315669D03*
X246685Y337357D03*
X255124Y335244D03*
X247025Y330512D03*
X251491Y357134D03*
X256588Y359005D03*
X244595Y363535D03*
X256532Y384895D03*
X247065Y385398D03*
X244546Y385315D03*
X253762Y385255D03*
X247797Y406029D03*
X250297D03*
X252797D03*
X245297D03*
X258798Y417594D03*
X254798Y417728D03*
X254813Y427018D03*
X252670Y443592D03*
X246465Y464893D03*
X251780Y460883D03*
X257568Y461513D03*
X255509Y472253D03*
X246109Y472465D03*
X251309Y472553D03*
X252036Y582131D03*
X245860Y575049D03*
X249909Y568653D03*
X259678Y581553D03*
X253187Y596382D03*
X249013Y628514D03*
X251803Y636704D03*
X254773Y644424D03*
X254303Y636744D03*
X256463Y639364D03*
X252173Y644344D03*
X249083Y636664D03*
X256513Y642494D03*
X246553Y636684D03*
X252486Y671772D03*
X244780Y682521D03*
X250795Y703150D03*
X251451Y697465D03*
X259170Y705138D03*
X258570Y722981D03*
X255310Y715915D03*
X248530Y721829D03*
X250630Y719457D03*
X248770Y724631D03*
X252940Y733567D03*
X256650Y778342D03*
X247900Y778823D03*
X252470Y785797D03*
X262955Y12663D03*
X266111Y29229D03*
X265789Y20990D03*
X268809Y16400D03*
X274990Y16396D03*
X272010Y40553D03*
X274510D03*
X274580Y74281D03*
X269920Y74318D03*
X272440Y76177D03*
X268080Y76416D03*
X272245Y89585D03*
X263703Y93847D03*
X271133Y92787D03*
X273973Y97645D03*
X262473Y106937D03*
X263683Y99902D03*
X268702Y107928D03*
X269010Y121648D03*
X264980Y121886D03*
X269192Y248209D03*
X272242Y244842D03*
X272620Y238653D03*
X260108Y240376D03*
X267118Y245587D03*
X271458Y241347D03*
X270260Y237037D03*
X266187Y249852D03*
X273521Y265849D03*
X260068Y262187D03*
X263268Y262370D03*
X263774Y256464D03*
X272464Y259964D03*
X269263Y252800D03*
X263029Y271139D03*
Y268139D03*
X273444Y270543D03*
X274944Y278363D03*
X270386Y280407D03*
X267386D03*
Y296047D03*
X261463Y296111D03*
X265825Y293987D03*
X268867Y293942D03*
X270444Y286183D03*
X265768Y287546D03*
X273444Y286183D03*
X273618Y295387D03*
X260045Y309615D03*
X268944Y309643D03*
X265944Y309640D03*
X261915Y302033D03*
X269380Y302736D03*
X264501Y303109D03*
X266939Y303281D03*
X274303Y303413D03*
X259820Y303800D03*
X267268Y311642D03*
X264287Y311687D03*
X270518Y311637D03*
X274832Y309687D03*
X265318Y326487D03*
X270525Y325754D03*
X262201Y328491D03*
X272967Y325842D03*
X275517D03*
X267030Y330147D03*
X262700Y325494D03*
X270485Y339030D03*
X264015Y336151D03*
X263173Y331794D03*
X267943Y339617D03*
X270293Y330540D03*
X272964Y330669D03*
X262379Y338103D03*
X262247Y334502D03*
X270071Y333021D03*
X272263Y334222D03*
X272352Y340900D03*
X269456Y355353D03*
X269886Y358753D03*
X260536Y374216D03*
X270293Y363972D03*
X273477Y385100D03*
X261663Y385193D03*
X267993Y390695D03*
X270796Y386643D03*
X266882Y388165D03*
X261539Y387755D03*
X264421Y384812D03*
X275497Y390758D03*
X263419Y393450D03*
X265162Y401391D03*
X272220Y401343D03*
X271720Y422587D03*
X265532Y422648D03*
X269630Y424884D03*
X274180Y424966D03*
X266822Y443297D03*
X275256Y445753D03*
X271035Y443051D03*
X273735Y443034D03*
X273509Y471649D03*
X263807Y461234D03*
X260609Y472453D03*
X264909Y472553D03*
X269109Y472353D03*
X275452Y483219D03*
X263924Y491754D03*
X269609Y576413D03*
X274309Y574653D03*
X261175Y569054D03*
X263792Y574203D03*
X268009Y570953D03*
X273480Y589201D03*
X269609Y588653D03*
X268717Y606015D03*
X261967Y608638D03*
Y605638D03*
X260064Y602993D03*
X261967Y614638D03*
X263467Y626638D03*
X269428Y622966D03*
X261967Y617638D03*
X263467Y623638D03*
X273938Y633084D03*
X273674Y640095D03*
X273548Y636471D03*
X266610Y654171D03*
X270040Y651241D03*
X269640Y655290D03*
X265913Y671772D03*
X261890Y664761D03*
X265550Y668415D03*
X274360Y673831D03*
X272460Y687889D03*
X267240Y682519D03*
X269420Y677062D03*
X272650Y693742D03*
X269410Y706003D03*
X267124Y707892D03*
X273510Y699749D03*
X266170Y694826D03*
X260680Y712988D03*
X271210Y718000D03*
X264600Y723086D03*
X270940Y722080D03*
X263430Y770417D03*
X264340Y778780D03*
X272175Y783074D03*
X278660Y10073D03*
X284505Y30676D03*
X287766Y21289D03*
X277472Y34959D03*
Y37459D03*
X280072Y34330D03*
X275766Y52772D03*
X275800Y50212D03*
X287270Y75018D03*
X283870Y74724D03*
X279100Y74447D03*
X289738Y76173D03*
X285543Y76867D03*
X281400Y75938D03*
X276969Y76247D03*
X276603Y92119D03*
X287423Y91857D03*
X281200Y98369D03*
X289720Y96094D03*
X278760Y101061D03*
X287599Y108831D03*
X278880Y108482D03*
X279161Y237817D03*
X276904Y252550D03*
X282166Y262922D03*
X281945Y260231D03*
X278811Y259135D03*
X279336Y264795D03*
X276444Y270543D03*
X282309Y270435D03*
X279444Y270543D03*
X277944Y278363D03*
X279386Y280407D03*
X276386D03*
X281767Y277742D03*
X290363Y286082D03*
X286132Y285953D03*
X281818Y290787D03*
X278918Y286887D03*
X276444Y286183D03*
X277020Y302298D03*
X282337Y308217D03*
X281859Y310862D03*
X277816Y309678D03*
X279754Y303269D03*
X276386Y311687D03*
X286071Y329184D03*
X278067Y325842D03*
X282167Y324242D03*
X288466Y325343D03*
X285704Y321809D03*
X277288Y334282D03*
X282234Y333792D03*
X285794Y339063D03*
X281205Y340997D03*
X279718Y333694D03*
X275602Y343811D03*
X289191Y341348D03*
X286020Y356454D03*
X277040Y376172D03*
X279863Y367513D03*
X286550Y374402D03*
X281450Y373151D03*
X288687Y385290D03*
X281864Y386178D03*
X284687Y386769D03*
X285390Y390550D03*
X288220Y389630D03*
X287067Y402358D03*
X280730Y393856D03*
X276400Y422341D03*
X280010Y422279D03*
X281190Y424966D03*
X278080Y424760D03*
X286210Y444926D03*
X289630Y444828D03*
X283212Y442286D03*
X286100Y442298D03*
X288742Y442090D03*
X287970Y446705D03*
X282000Y444966D03*
X279112Y444954D03*
X276626Y442913D03*
X279990Y442071D03*
X280210Y460762D03*
X287567Y470649D03*
Y467649D03*
X280380Y467284D03*
X278990Y464793D03*
X277470Y481197D03*
X280970D03*
X288009Y495653D03*
X284024Y502595D03*
X290323D03*
X280874Y556139D03*
X279658Y574443D03*
X285530Y573002D03*
X283650Y589044D03*
X278109Y589238D03*
X287997Y649064D03*
X280880Y650295D03*
X278699Y656491D03*
X279090Y668504D03*
X279785Y663876D03*
X289365Y665845D03*
Y673719D03*
X279843Y675688D03*
X278350Y687309D03*
X275710Y681593D03*
X289248Y680521D03*
X275560Y697804D03*
X279060Y693306D03*
X284760Y707022D03*
X286798Y704143D03*
X278370Y705093D03*
X277475Y695723D03*
X289060Y722193D03*
X281830Y722184D03*
X285130Y714433D03*
X275880Y722141D03*
X285880Y722268D03*
X289150Y718548D03*
X280210Y734805D03*
X288390Y734796D03*
X284020Y724956D03*
X284532Y747493D03*
X275627Y777692D03*
X281930Y773190D03*
X286722Y785929D03*
X292313Y76345D03*
X305880Y76361D03*
X299220Y76196D03*
X302953Y76167D03*
X295867Y76567D03*
X301870Y92072D03*
X296870D03*
X291927Y102991D03*
X293505Y94965D03*
X296927Y102991D03*
X303220Y98397D03*
X299590Y121289D03*
X299850Y124708D03*
X302930Y132994D03*
X296176Y249585D03*
X299776Y248010D03*
X301511Y262204D03*
X300477Y265010D03*
X296210Y253187D03*
X300310Y253842D03*
Y257242D03*
X292710Y266542D03*
X301473Y282650D03*
X297810Y280709D03*
X301723Y279150D03*
X301182Y291966D03*
X294382D03*
X305132Y286867D03*
X298332D03*
X301732D03*
X301795Y310398D03*
X296639Y308057D03*
X305250Y310342D03*
X300201Y300874D03*
X303197Y304297D03*
X297073Y329159D03*
X298452Y340487D03*
X305880Y339046D03*
X306820Y342146D03*
X299410Y331201D03*
X303759Y331478D03*
X305446Y359450D03*
X295527Y359812D03*
X303171Y374224D03*
X291686Y375177D03*
X295388Y375644D03*
X293290Y389737D03*
X291382Y385457D03*
X299533Y394056D03*
X291860Y442927D03*
X292170Y445986D03*
X300040Y459733D03*
X303631Y475607D03*
Y472607D03*
X297370Y498563D03*
X300209Y495853D03*
X305708Y503043D03*
X295047Y554565D03*
X304410Y572782D03*
X306229Y600263D03*
X301796Y603917D03*
X298303Y613184D03*
X302870Y633981D03*
X297162Y642065D03*
X293843Y642536D03*
X303110Y639381D03*
X301070Y655920D03*
X292850Y656359D03*
X304870Y655747D03*
X306294Y659156D03*
X297394Y657033D03*
X302772Y659604D03*
X301360Y652183D03*
X306294Y667156D03*
Y663156D03*
Y675156D03*
Y671156D03*
X300880Y664296D03*
X294120Y668391D03*
X295890Y662662D03*
X297770Y674720D03*
X305979Y691156D03*
X306145Y683156D03*
X305979Y687156D03*
X306294Y679156D03*
X292970Y682450D03*
X295950Y689520D03*
X293068Y677108D03*
X296858Y702544D03*
X297300Y697221D03*
X293286Y703504D03*
X305990Y697189D03*
X303681Y714421D03*
X305213Y720393D03*
X293300Y718944D03*
X296885Y718059D03*
X297223Y715523D03*
X291318Y713875D03*
X302810Y733807D03*
X298590Y733669D03*
X293480Y725080D03*
X295700Y733133D03*
X293440Y748380D03*
X291340Y771217D03*
X295100Y786269D03*
X299249Y771403D03*
X304740Y777277D03*
X317334Y10955D03*
X322640Y9774D03*
X317334Y28955D03*
X318910Y74595D03*
X314310Y74540D03*
X307740Y74263D03*
X309730Y76232D03*
X321283Y76327D03*
X316623Y76047D03*
X312402Y76587D03*
X315083Y90207D03*
X311553Y92347D03*
X310850Y99620D03*
X320740Y98599D03*
X312223Y96407D03*
X317970Y95961D03*
X313583Y122387D03*
X311290Y247249D03*
X312680Y258353D03*
X307204Y304212D03*
X310623Y313589D03*
X313123D03*
X320623D03*
X318123D03*
X315623D03*
X311740Y325839D03*
X313980Y335813D03*
X314550Y331564D03*
X318480Y335039D03*
X321130Y342418D03*
X309190Y336959D03*
X319807Y346376D03*
X321150Y357730D03*
X319288Y350376D03*
X307410Y348380D03*
X313222Y374229D03*
X322255Y371935D03*
X321297Y367739D03*
X319363Y372149D03*
X310484Y383312D03*
X321144Y399643D03*
X318644D03*
X316190Y413299D03*
X317140Y421775D03*
X321910Y410139D03*
X311610Y432528D03*
X313530Y436460D03*
X315940Y438104D03*
X319478Y429389D03*
X308220Y432552D03*
X322599Y432505D03*
X309440Y426404D03*
X318950Y432473D03*
X321357Y456709D03*
X307800Y467859D03*
X310380Y473942D03*
X321246Y472669D03*
X315980Y472128D03*
X307670Y473605D03*
X320080Y512736D03*
X318678Y540966D03*
X321828Y541682D03*
X313419Y594040D03*
X313227Y590232D03*
X310919Y594040D03*
X310627Y590232D03*
X315957Y594127D03*
X320094Y604114D03*
X320512Y613603D03*
X308741Y623871D03*
X311311Y618197D03*
X317492Y618193D03*
X314940Y642067D03*
X310453Y642451D03*
X320360Y642275D03*
X311382Y635432D03*
X316184Y662630D03*
X314614Y690767D03*
X316184Y687630D03*
X316165Y693404D03*
X313230Y702465D03*
X307113Y713003D03*
X321820Y712680D03*
X311990Y717601D03*
X319620Y716403D03*
X309531Y714298D03*
X312972Y712693D03*
X318090Y712846D03*
X307280Y733705D03*
X321930Y724895D03*
X314930Y724533D03*
X307146Y769416D03*
X315020Y780559D03*
X320657Y779595D03*
X320440Y771967D03*
X323334Y12377D03*
X323871Y25812D03*
Y16812D03*
Y19812D03*
Y28812D03*
X327117Y31840D03*
X323640Y74393D03*
X326140Y76196D03*
X335668Y92822D03*
X330668D03*
X325360Y92517D03*
X324070Y88861D03*
X325970Y98817D03*
X327430Y108208D03*
X327190Y103818D03*
X337630Y106304D03*
X334720Y102184D03*
X323032Y122237D03*
X331583Y128717D03*
X336495Y290569D03*
X328526Y308696D03*
X334478Y299604D03*
X323123Y313589D03*
X336720Y310846D03*
X337293Y316660D03*
X333540Y315590D03*
X333726Y353801D03*
X333440Y349221D03*
X327058Y358376D03*
X323040Y354485D03*
X336850Y380332D03*
X326282Y399743D03*
X323644Y399643D03*
X331090Y424304D03*
X331900Y419317D03*
X336740Y417069D03*
X328290Y424304D03*
X324940Y413899D03*
X334420Y428660D03*
X326190Y448621D03*
X329120Y449203D03*
X327780Y445819D03*
X331360Y447306D03*
X322986Y467109D03*
X330115Y490303D03*
X335162Y502791D03*
X326740Y495763D03*
X329672Y502057D03*
X326170Y518386D03*
X335860Y516486D03*
X336010Y531598D03*
X329348Y533403D03*
X324927Y546013D03*
X328592Y541146D03*
X328352Y545412D03*
X325588Y541447D03*
X332408Y544097D03*
X323088Y561503D03*
X323188Y564503D03*
X330388Y565803D03*
X332388Y567703D03*
X328088Y567503D03*
X323931Y589733D03*
X323346Y621930D03*
X329110Y623514D03*
X330440Y639504D03*
X328032Y642674D03*
X337070Y639759D03*
X326350Y638968D03*
X332710Y642694D03*
X328760Y657144D03*
X327540Y653432D03*
X335610Y658177D03*
X332747Y655636D03*
X332190Y659883D03*
X329912Y662383D03*
X335915Y675011D03*
X335390Y667895D03*
X326890Y676159D03*
X327257Y672408D03*
X333180Y665611D03*
X335130Y670744D03*
X334313Y663113D03*
X327500Y667244D03*
X324970Y665128D03*
X337030Y677894D03*
X337798Y686721D03*
X324120Y703114D03*
X336110Y693934D03*
X331520Y701642D03*
X332720Y698170D03*
X330410Y712895D03*
X325560Y713391D03*
X329590Y724283D03*
X334640Y725035D03*
X338270Y733387D03*
X338460Y724585D03*
X326280Y775980D03*
X337800Y774677D03*
X346600Y38561D03*
X346150Y36030D03*
X353060Y61504D03*
X349490Y57698D03*
X352578Y74292D03*
X339750Y73383D03*
X340543Y88647D03*
X345463Y90837D03*
X353713Y93057D03*
X344873Y94847D03*
X343070Y99372D03*
X340450Y101914D03*
X343743Y120967D03*
X351503Y130972D03*
Y127972D03*
X341693Y286010D03*
X340792Y307107D03*
X353903Y314077D03*
X353841Y306194D03*
X339370Y329176D03*
X341910Y325739D03*
X344720D03*
X339600Y332076D03*
X343880Y356989D03*
X349110Y375767D03*
X352420Y375672D03*
X346020Y374075D03*
X343430Y385937D03*
X343770Y382166D03*
X351650Y420270D03*
X346862Y424850D03*
X345270Y452745D03*
X346750Y466532D03*
X352890Y479656D03*
X348000Y479150D03*
X352260Y483029D03*
X338762Y479636D03*
X339506Y482841D03*
X348220Y486484D03*
X352160Y502138D03*
X351250Y499752D03*
X348870Y501571D03*
X343420Y497966D03*
X353400Y507260D03*
X353460Y504536D03*
X348190Y511550D03*
X353120Y510003D03*
X350690Y516376D03*
X340902Y503742D03*
X352940Y518025D03*
X341512Y512429D03*
X350902Y512520D03*
X346350Y517286D03*
X340182Y531787D03*
X351110Y531835D03*
X340330Y541931D03*
X341011Y537828D03*
X342190Y565848D03*
X351964Y599332D03*
X340340Y638054D03*
X340669Y644827D03*
X348480Y638558D03*
X345580Y638109D03*
X347670Y642285D03*
X351722Y659319D03*
X340630Y655093D03*
X351730Y649206D03*
X353902Y667128D03*
X351730Y663450D03*
X340530Y675658D03*
X351720Y670018D03*
X338970Y670776D03*
X340870Y665042D03*
X353260Y688757D03*
X351810Y706800D03*
X339750Y695271D03*
X339010Y700406D03*
X338926Y697752D03*
X352400Y722132D03*
X339300Y716800D03*
X342230Y720936D03*
X341190Y712379D03*
X352010Y713968D03*
X342230Y709384D03*
X345610Y733982D03*
X354060Y734790D03*
X350720Y745722D03*
X344710Y785782D03*
X350450Y784982D03*
X363025Y12926D03*
X366159Y21822D03*
X361930Y60031D03*
X367300Y60442D03*
X365670Y64458D03*
X362133Y90877D03*
X367776Y91746D03*
X358343Y90948D03*
X369670Y99845D03*
X361470Y101757D03*
X354943Y104191D03*
X354448Y108092D03*
X367350Y123927D03*
X365283Y128125D03*
X364220Y296795D03*
X365970Y299194D03*
X356835Y313894D03*
X369280Y300916D03*
X367220Y303202D03*
X369040Y316735D03*
X369934Y322946D03*
X365026Y332478D03*
X362540Y361443D03*
X354690Y377000D03*
X364645Y377065D03*
X364880Y384455D03*
X364580Y391273D03*
X366140Y407639D03*
X360350Y395873D03*
X355250Y420679D03*
X365850Y414874D03*
X368660Y449478D03*
X369500Y445873D03*
X354565Y451562D03*
X354750Y445325D03*
X369507Y464391D03*
X358182Y531231D03*
X357820Y534561D03*
X368825Y539776D03*
X369918Y592253D03*
X369848Y588903D03*
X360647Y602636D03*
X354973Y605588D03*
Y602588D03*
Y611588D03*
X361473Y620588D03*
X354973Y614588D03*
Y620588D03*
Y623588D03*
X361562Y645175D03*
X363530Y629727D03*
X365990Y645272D03*
X367870Y650239D03*
X364980Y655266D03*
X363340Y650512D03*
X361650Y658537D03*
X361580Y652755D03*
X368200Y672132D03*
X368100Y668133D03*
X361810Y675011D03*
X365620Y663069D03*
X361660Y671306D03*
X365380Y668972D03*
X365160Y672922D03*
X361760Y668716D03*
X367066Y681094D03*
X364320Y680434D03*
X367496Y690248D03*
X361510Y680886D03*
X362040Y684875D03*
X364649Y684022D03*
X364765Y687963D03*
X365090Y676923D03*
X367480Y705169D03*
X367614Y693053D03*
X361580Y703860D03*
X363590Y702324D03*
X364115Y692990D03*
X367520Y701710D03*
X367350Y713661D03*
X357830Y718682D03*
X354520Y728701D03*
X363460Y735388D03*
X364750Y727821D03*
X364090Y748565D03*
X354420Y749198D03*
X357610Y748302D03*
X366860Y739956D03*
X354870Y771388D03*
X360160Y775523D03*
X363300Y781303D03*
X367904Y778327D03*
X371180Y17789D03*
X370960Y20577D03*
X381907Y21507D03*
X383280Y59940D03*
X376006Y60991D03*
X383247Y64141D03*
X373560Y63973D03*
X372776Y91746D03*
X382087Y103647D03*
X380483Y99047D03*
X378733Y105987D03*
X384863Y95437D03*
X376100Y108780D03*
X376723Y94178D03*
X378183Y124904D03*
X374040Y304980D03*
X373640Y301078D03*
X370460Y305908D03*
X371090Y303487D03*
X384248Y319157D03*
X372080Y330574D03*
X379560Y374955D03*
X379720Y372257D03*
X378830Y386352D03*
X382620Y391882D03*
X379300Y380862D03*
X379286Y378015D03*
X379750Y383965D03*
X382190Y388077D03*
X376600Y408045D03*
X382680Y408202D03*
X371260Y412879D03*
X383750Y437058D03*
X372320Y439514D03*
X371950Y430527D03*
X378910Y430874D03*
X371080Y448276D03*
X372710Y445705D03*
X375190Y463996D03*
X381239Y467171D03*
X371080Y481589D03*
X374207Y479329D03*
X381760Y496004D03*
X374203Y491029D03*
X376540Y498385D03*
X383617Y517862D03*
X373538Y520213D03*
X376528Y520138D03*
X379733Y549392D03*
X370309Y550322D03*
X377150Y543151D03*
X376490Y540574D03*
X382596Y537379D03*
X382333Y540414D03*
X385410Y566122D03*
X373448Y589053D03*
X373518Y592403D03*
X383034Y640267D03*
X373218Y634217D03*
X382580Y637413D03*
X379093Y657739D03*
X376650Y654157D03*
X379492Y650239D03*
X376089Y646156D03*
X373680Y662417D03*
X376087Y670156D03*
X377211Y673197D03*
X379461Y675246D03*
X379462Y666156D03*
X379791Y679454D03*
X376946Y689985D03*
X377681Y694244D03*
X377679Y701168D03*
X377669Y706237D03*
X377100Y697218D03*
X371170Y711574D03*
X382960Y711431D03*
X372110Y720308D03*
X376190Y711259D03*
X375548Y731459D03*
X375834Y727459D03*
X377840Y724388D03*
X376770Y734898D03*
X373500Y748457D03*
X392600Y20548D03*
X389240D03*
X397655Y21336D03*
X392250Y59899D03*
X389690Y60665D03*
X401310Y61439D03*
X397790Y61360D03*
Y69610D03*
X390355Y75775D03*
X401220Y65155D03*
X392493Y92647D03*
X400163Y99177D03*
X391310Y99570D03*
X399613Y104657D03*
X391233Y96093D03*
X398088Y128455D03*
X393088D03*
X399598Y260251D03*
X398258Y252341D03*
X394378Y260501D03*
X399608Y275211D03*
X393458Y282931D03*
X392508Y275581D03*
X398038Y292571D03*
X399880Y319568D03*
X390080Y331575D03*
X389740Y404725D03*
X395740Y407528D03*
X393370Y411618D03*
X392076Y470970D03*
X387080Y486400D03*
X385940Y482478D03*
X388890Y480439D03*
X386410Y477576D03*
X389670Y477262D03*
X388982Y496939D03*
X395690Y512774D03*
X396350Y532016D03*
X396558Y522251D03*
X396470Y527847D03*
X396048Y540127D03*
X395922Y536127D03*
X396590Y549310D03*
X399590Y553502D03*
X390000Y567345D03*
X396520Y567444D03*
X393596Y567630D03*
X401091Y587054D03*
X398386Y587126D03*
X401422Y597270D03*
Y599770D03*
X398822Y600399D03*
X391447Y611973D03*
X394389Y604053D03*
X401353Y624007D03*
X399223Y644930D03*
X395701Y637430D03*
X399440Y637340D03*
X394380Y643389D03*
X396366Y653229D03*
X399363Y653588D03*
X389856Y645705D03*
X386173Y665065D03*
X391938Y672320D03*
X392097Y676231D03*
X399873Y666411D03*
X396550Y680266D03*
X399829Y690191D03*
X400968Y686699D03*
X400408Y681193D03*
X390660Y686923D03*
X391910Y696742D03*
X392080Y692796D03*
X391740Y705957D03*
X398620Y701411D03*
X390950Y701922D03*
X396150Y708926D03*
X400730Y721954D03*
X394840Y711437D03*
X404310Y65213D03*
X410713Y76187D03*
X404813Y93887D03*
X407303Y95117D03*
X408072Y109146D03*
X404738Y260421D03*
X402948Y253251D03*
X405970Y256489D03*
X401618Y267351D03*
X403148Y270191D03*
X405248Y272731D03*
X403628Y292201D03*
X408790Y317049D03*
X411240Y316482D03*
X414870Y455166D03*
Y450976D03*
X406352Y471405D03*
X410607Y485620D03*
X413607D03*
X409985Y508431D03*
X413138Y504813D03*
X413222Y508054D03*
X411439Y516956D03*
X407865Y516627D03*
X405348Y506316D03*
X402458Y505903D03*
X401556Y508937D03*
X409251Y521763D03*
X412088Y521721D03*
X407776Y527426D03*
X405954Y532502D03*
X404336Y545280D03*
X408486Y537333D03*
X416515Y547602D03*
X404578Y551838D03*
X408736Y551529D03*
X413342Y556219D03*
X406884Y594176D03*
X406881Y591322D03*
X412783Y605500D03*
X416454Y621319D03*
X413105Y613739D03*
X403904Y618333D03*
X410085Y618329D03*
X409520Y637387D03*
X414760Y636225D03*
X403970Y642364D03*
X406100Y631851D03*
X413535Y646804D03*
X411982Y660285D03*
X413718Y655267D03*
X410918Y649363D03*
X413966Y675624D03*
X415218Y664203D03*
X411675Y672654D03*
X411065Y667516D03*
X414183Y686151D03*
X411862Y688027D03*
X413643Y680004D03*
X412250Y683196D03*
X411149Y678387D03*
X412878Y693183D03*
X414550Y707464D03*
X414318Y700979D03*
X414810Y696968D03*
X402540Y710649D03*
X412080Y719034D03*
X414080Y721334D03*
X415730Y710897D03*
X406720Y723395D03*
X409010Y726147D03*
X415780Y747078D03*
X421893Y123537D03*
X421640Y228403D03*
Y223403D03*
X428405Y245194D03*
X424961Y241203D03*
X418905Y245694D03*
X426992Y250016D03*
X422528Y253531D03*
X426335Y267062D03*
X418575Y263691D03*
X420858Y261331D03*
X427817Y258829D03*
X421728Y279141D03*
X428748Y275222D03*
X418588Y286681D03*
X421128Y292601D03*
X423178Y284601D03*
X427909Y286759D03*
X427468Y292287D03*
X421710Y424527D03*
X430340Y416573D03*
X432450Y418766D03*
X422120Y418288D03*
X432960Y414886D03*
X422080Y414644D03*
Y410454D03*
X421770Y433187D03*
X422860Y441790D03*
X422760Y445581D03*
X425870Y449509D03*
X422460Y449467D03*
X429670Y449552D03*
X419420Y453168D03*
X428747Y463314D03*
X419420Y457358D03*
X428747Y468770D03*
X431280Y514223D03*
X431356Y516836D03*
X422050Y517028D03*
X425999Y516211D03*
X424873Y513921D03*
X426068Y546048D03*
X417979Y545352D03*
X428039Y548119D03*
X421461Y547703D03*
X420883Y556729D03*
X428039Y556539D03*
X423861Y556535D03*
X431145Y556608D03*
X424904Y586283D03*
X429340Y596874D03*
X425151Y608429D03*
X431520Y607039D03*
X420245Y636004D03*
X417422Y637592D03*
X432180Y647458D03*
X425334Y656419D03*
X422007Y652732D03*
X423623Y645396D03*
X422026Y656883D03*
X429820Y656709D03*
X421080Y665945D03*
X422222Y675226D03*
X426100Y667884D03*
X427900Y679709D03*
X430861Y679156D03*
X422981Y690351D03*
X430862Y691156D03*
X430813Y687156D03*
X427210Y691934D03*
X423055Y696713D03*
X430618Y699156D03*
X430667Y703156D03*
X430731Y707156D03*
X430813Y695156D03*
X427230Y707377D03*
X426391Y701173D03*
X423242Y707949D03*
X425590Y695895D03*
X421350Y694003D03*
X430738Y711156D03*
X427130Y717871D03*
X421730Y717398D03*
X429240Y721014D03*
X424410Y718429D03*
X417330Y717420D03*
X431440Y723955D03*
X420290Y733741D03*
X423900Y736055D03*
X424200Y733399D03*
X426440Y724240D03*
X421690Y779548D03*
X417880Y786361D03*
X428250Y772054D03*
X426900Y779752D03*
X442380Y75513D03*
X439670Y70044D03*
X446920Y78358D03*
X447715Y97926D03*
X446522Y146932D03*
X444550Y184057D03*
X442520Y223623D03*
X441580Y250730D03*
X443212Y240957D03*
X441498Y266731D03*
X441792Y259473D03*
X445540Y288853D03*
X445890Y283317D03*
X438340Y403375D03*
X439150Y400930D03*
X443240Y401984D03*
X446830Y400551D03*
X445900Y403460D03*
X436370Y410543D03*
X444020Y410374D03*
X439830D03*
X446660Y413325D03*
X446950Y417162D03*
X440900Y446260D03*
X436710D03*
X444850Y446337D03*
X438390Y456129D03*
X438520Y452324D03*
X433720Y449467D03*
X444920Y485259D03*
X447770Y485290D03*
X437716Y476295D03*
X445366Y490657D03*
X445199Y494590D03*
X439749Y506523D03*
X439762Y515540D03*
Y523757D03*
X447781Y523888D03*
X434605Y521488D03*
X442763Y549595D03*
X445838Y538085D03*
X435998Y539726D03*
X434203Y542897D03*
X438722Y538842D03*
X441063Y540563D03*
X448329Y534995D03*
X441326Y556050D03*
X437832Y556374D03*
X434187Y556444D03*
X442240Y553337D03*
X441230Y587341D03*
X447830Y588739D03*
X446378Y582681D03*
X435319Y600123D03*
X440040Y608537D03*
X437120Y612933D03*
X448460Y625960D03*
X445604Y629045D03*
X437100Y643793D03*
X446500Y645075D03*
X443850Y634754D03*
X439250Y630973D03*
X434681Y642639D03*
X435420Y647117D03*
X437509Y648996D03*
X435972Y655595D03*
X444700Y651900D03*
X445270Y660832D03*
X447210Y665143D03*
X436000Y675706D03*
X435539Y671628D03*
X436445Y667628D03*
X447161Y673564D03*
X444458Y669350D03*
X440688Y684438D03*
Y689438D03*
X440690Y702386D03*
X440688Y694438D03*
X442650Y719485D03*
X446260Y722014D03*
X444530Y723917D03*
X440660Y712065D03*
X439200Y722093D03*
X442120Y724781D03*
X447680Y733564D03*
X444370Y770152D03*
X434540Y778500D03*
X441006Y785297D03*
X458120Y44721D03*
X464170Y56436D03*
X458598Y77967D03*
X461516Y78275D03*
X461594Y99342D03*
X449538Y105144D03*
X453168D03*
X453940Y98586D03*
X460412Y105704D03*
X457912D03*
X462912D03*
X461880Y150596D03*
X454763Y183503D03*
X453340Y185670D03*
X457482Y183523D03*
X462790Y183489D03*
X459000Y200500D03*
X450650Y203785D03*
X453620Y245162D03*
X459990Y245930D03*
X456800Y259233D03*
X459108Y253181D03*
X449860Y267121D03*
X456530Y256034D03*
X449860Y272121D03*
X452900Y281647D03*
X453810Y289325D03*
X451790Y300129D03*
X448970Y403846D03*
X451950Y402434D03*
X463540Y495717D03*
X457537Y495546D03*
X454770Y495587D03*
X450813Y492993D03*
X463565Y515723D03*
X452895Y510061D03*
X449402Y515514D03*
X451504Y529734D03*
X450540Y521331D03*
X463991Y531504D03*
X451325Y525981D03*
X456722Y529536D03*
X454022Y541052D03*
X463031Y543563D03*
X453917Y550069D03*
X450367Y540720D03*
X453700Y545047D03*
X453854Y555069D03*
X455890Y592792D03*
X450778Y583106D03*
X462270Y612911D03*
X459690Y626423D03*
X464050Y633877D03*
X458903Y644884D03*
X461997Y654507D03*
X463178Y647483D03*
X460587Y669424D03*
X457138Y663251D03*
X463020Y661023D03*
X464330Y663251D03*
X458820Y674137D03*
X459950Y722720D03*
X453960Y723142D03*
X449060Y721761D03*
X457060Y722427D03*
X460822Y712620D03*
X451820Y712210D03*
X454070Y714226D03*
X455410Y734113D03*
X450410Y733682D03*
X451320Y725044D03*
X461565Y785806D03*
X463750Y780452D03*
X454120Y785923D03*
X475310Y59746D03*
X475030Y63879D03*
X479450Y63721D03*
X471500Y138000D03*
X473200Y140300D03*
X468400Y135800D03*
X470324Y133424D03*
X474813Y162220D03*
X467473Y159766D03*
X473951Y157235D03*
X473950Y172124D03*
X475760Y168747D03*
X472670Y166398D03*
X473580Y177859D03*
X474630Y174843D03*
X480220Y185766D03*
X475770Y186451D03*
X468452Y197934D03*
X471300Y201900D03*
X476400Y203100D03*
X478000Y212500D03*
X466200Y207300D03*
X471795Y267941D03*
X464810Y311253D03*
X470090Y332824D03*
X475190Y339013D03*
X465913Y402659D03*
X465883Y399834D03*
X480118Y479107D03*
Y474107D03*
X466307Y495676D03*
X467677Y510055D03*
X467496Y513179D03*
X466587Y515764D03*
X467586Y506807D03*
X471804Y561085D03*
Y556085D03*
X471190Y593964D03*
X468740Y585897D03*
X469890Y596580D03*
X473294Y613207D03*
X476320Y629280D03*
X465580Y641417D03*
X469229Y638135D03*
X475820Y635422D03*
X474946Y659376D03*
X468810Y652180D03*
X479512Y649436D03*
X468540Y655799D03*
X466980Y667059D03*
X469977Y676496D03*
X468260Y664366D03*
X469467Y679915D03*
X479409Y682305D03*
X479354Y677054D03*
X477710Y722299D03*
X466620Y714137D03*
X473940Y714184D03*
X470550Y724034D03*
X473560Y724951D03*
X465850Y733428D03*
X476980Y736594D03*
X476160Y734205D03*
X471780Y786300D03*
X486810Y60785D03*
X483240Y60546D03*
X487030Y68075D03*
X488438Y109623D03*
X492955Y99440D03*
X494355Y108674D03*
X491875Y125222D03*
X487140Y123397D03*
X484350Y112811D03*
X487020Y119754D03*
X494910Y133316D03*
X487857Y152147D03*
X488570Y147486D03*
X492424Y142234D03*
X494467Y148867D03*
X487740Y161235D03*
X488220Y157515D03*
X490130Y163086D03*
X493670Y171871D03*
X489040Y169483D03*
X482500Y184169D03*
X487080Y180918D03*
X482980Y181071D03*
X488850Y175419D03*
X494210Y175035D03*
X487839Y194142D03*
X487464Y198566D03*
X488017Y203716D03*
X486370Y189279D03*
X487168Y214568D03*
X491320Y231809D03*
X492700Y223800D03*
X484169Y272867D03*
X484780Y314090D03*
X494850Y315733D03*
X480830Y333921D03*
X486300Y422150D03*
X481300D03*
X495500Y447465D03*
X482880Y467935D03*
Y462935D03*
X492260Y482826D03*
X494980Y482979D03*
X490334Y497342D03*
X485510Y536673D03*
X483209Y545250D03*
Y550250D03*
X490661Y547148D03*
X489962Y540849D03*
X483838Y566194D03*
Y556148D03*
Y561148D03*
Y571194D03*
X485738Y587125D03*
X490738D03*
X481340Y593296D03*
X494238Y600441D03*
X490600Y608136D03*
X489800Y600200D03*
X487832Y624429D03*
X490040Y622140D03*
X491380Y639279D03*
X495900Y641804D03*
X480310Y642224D03*
X492310Y650516D03*
X482180Y646278D03*
X481253Y654837D03*
X493020Y646701D03*
X484700Y660355D03*
X482398Y673087D03*
X482544Y668042D03*
X491044Y667604D03*
X491060Y671604D03*
X490120Y662703D03*
X492770Y665090D03*
X492294Y682347D03*
X483056Y679628D03*
X481227Y685366D03*
X491167Y687507D03*
X481227Y691366D03*
X494340Y691623D03*
X491067Y699656D03*
X491380Y694656D03*
X490900Y706145D03*
X481227Y696366D03*
X495560Y694781D03*
X488180Y719244D03*
X490890Y714898D03*
X488090Y710545D03*
X480620Y734244D03*
X480770Y778125D03*
X485870Y776087D03*
X491720Y776713D03*
X495110Y771733D03*
X502900Y57670D03*
X496955Y99958D03*
X508955Y99978D03*
X500955Y100139D03*
X504955Y99830D03*
X500310Y109211D03*
X497430Y124024D03*
X504750Y111749D03*
X509691Y112938D03*
X499456Y128666D03*
X509710Y127269D03*
X500215Y136449D03*
X502183Y156709D03*
X500963Y162261D03*
X496360Y167221D03*
X501040Y177297D03*
X498940Y179744D03*
X510000Y173500D03*
X502999Y180541D03*
X499154Y194198D03*
X509100Y191900D03*
X505580Y192555D03*
X499225Y205296D03*
X506234Y207368D03*
X504941Y227859D03*
X498867Y227773D03*
X499405Y242877D03*
X507000Y239000D03*
X504160Y255584D03*
X511070Y310719D03*
X509140Y338005D03*
X497111Y388567D03*
X502111D03*
X509486Y433829D03*
X497818Y440265D03*
X506456Y446928D03*
X502938Y463823D03*
X505843Y465018D03*
X498119Y470011D03*
X511230Y499059D03*
X506230D03*
X498920Y523803D03*
X503958Y529405D03*
X504613Y525200D03*
X501331Y528932D03*
X503338Y549825D03*
Y544825D03*
X500138Y563025D03*
Y558625D03*
X500338Y566425D03*
X500438Y574925D03*
X500419Y578644D03*
X500538Y572025D03*
X500338Y569425D03*
X500538Y588525D03*
X505738Y590525D03*
X500098Y608885D03*
X509238Y608515D03*
X508024Y613598D03*
X500538Y600925D03*
X504980Y616425D03*
X508400Y617803D03*
X502080Y622999D03*
X498350Y627580D03*
X505780Y642543D03*
X501120Y633249D03*
X510700Y634300D03*
X496690Y633589D03*
X501940Y644073D03*
X504836Y657097D03*
X503680Y659666D03*
X505690Y654419D03*
X508061Y645381D03*
X504295Y649612D03*
X498040Y675306D03*
X498870Y668324D03*
X504114Y670830D03*
X496453Y670876D03*
X501914Y675624D03*
X504241Y665809D03*
X497320Y665216D03*
X506376Y687436D03*
X506470Y683512D03*
X496577Y684553D03*
X505580Y679105D03*
X496277Y678185D03*
X501540Y681970D03*
X506409Y691373D03*
X500710Y706582D03*
X497350Y699767D03*
X506092Y697575D03*
X510608Y717448D03*
X499842Y710582D03*
X499452Y714582D03*
X498080Y733252D03*
X509855Y724107D03*
X500260Y729094D03*
X501604Y733003D03*
X501890Y746663D03*
X507935Y785704D03*
X511770Y779940D03*
X499270Y776431D03*
X504440Y772548D03*
X513120Y72069D03*
X512955Y100428D03*
X524955Y99359D03*
X516955Y100333D03*
X520955Y100444D03*
X512878Y108635D03*
X519625Y108543D03*
X526835Y108314D03*
X525570Y124623D03*
X516146Y113121D03*
X522111Y113310D03*
X518640Y125539D03*
X518725Y170525D03*
X512600Y178900D03*
X515600Y172800D03*
X521320Y178184D03*
X516100Y178100D03*
X526621Y177079D03*
X512200Y204200D03*
X526443Y194116D03*
X514500Y194300D03*
X525293Y191705D03*
X515231Y191334D03*
X520015Y194584D03*
X523593Y198171D03*
X512200Y196000D03*
X520068Y207142D03*
X516551Y214987D03*
X512160Y217073D03*
X526657Y207363D03*
X524405Y212531D03*
X514766Y208222D03*
X515675Y234555D03*
X524675Y234766D03*
X517189Y226229D03*
X517670Y247527D03*
X515675Y254098D03*
X525480Y268959D03*
X518590Y310129D03*
X526250Y310940D03*
X519650Y320384D03*
X522420Y315475D03*
X517260Y315978D03*
X523930Y321642D03*
X514400Y340829D03*
X520510Y337299D03*
X527438Y340353D03*
X526440Y422428D03*
X527300Y417368D03*
X517929Y439676D03*
X523667Y438452D03*
X522379Y431974D03*
X512867Y443679D03*
X516353Y443517D03*
X523838Y442723D03*
X525603Y480187D03*
X525638Y484023D03*
X519938Y493125D03*
X524938D03*
X514430Y511801D03*
X519430D03*
X518938Y540425D03*
X521938Y540325D03*
X516380Y540364D03*
X525338Y540125D03*
X516738Y562425D03*
X513738D03*
X515413Y590950D03*
X524638Y590225D03*
X520228Y590335D03*
X525570Y602466D03*
X514058Y605055D03*
X523800Y611145D03*
X520370Y625158D03*
X526300Y623621D03*
X518920Y615387D03*
X511910Y638722D03*
X514320Y641085D03*
X515438Y649996D03*
X525692Y654862D03*
X517328Y655529D03*
X521516Y650576D03*
X517806Y670102D03*
X517222Y673917D03*
X518800Y665776D03*
X526610Y672286D03*
X515541Y661845D03*
X526430Y664730D03*
X518382Y678247D03*
X515429Y692278D03*
X526600Y679117D03*
X517888Y687901D03*
X518947Y685122D03*
X527111Y686052D03*
X515429Y697278D03*
X512548Y722093D03*
X514620Y713193D03*
X517443Y717011D03*
X517775Y711203D03*
X522865Y711178D03*
X514498Y716473D03*
X516940Y735683D03*
X521800Y732667D03*
X514420Y733131D03*
X524576Y733227D03*
X512610Y747115D03*
X525110Y774395D03*
X519440Y772861D03*
X542180Y93534D03*
X539510Y108742D03*
X536955Y100257D03*
X532955Y108669D03*
X528955Y99781D03*
X532955Y100604D03*
X535960Y112850D03*
X527613Y113373D03*
X542700Y112881D03*
X538655Y151415D03*
X538294Y159415D03*
X529272Y178311D03*
X542002Y180100D03*
X539500Y196500D03*
X536232Y192086D03*
X529592Y192999D03*
X533474Y196500D03*
X541657Y207645D03*
X532320Y209470D03*
X538525Y213425D03*
X532500Y206500D03*
X534208Y227832D03*
X528105Y230594D03*
X536972Y242993D03*
X536476Y238993D03*
X535772Y250076D03*
X539267Y267102D03*
X532794Y282068D03*
X530119Y280101D03*
X528680Y317349D03*
X541380Y340358D03*
X543110Y333848D03*
X536180Y341432D03*
X536170Y336603D03*
X531795Y340409D03*
X531430Y337074D03*
X527603Y337208D03*
X540700Y418852D03*
X541650Y422280D03*
X536440Y421973D03*
X530940Y422207D03*
X529968Y440216D03*
X529028Y430469D03*
X535352Y440414D03*
X540141Y442994D03*
X534738Y445523D03*
X541838Y450723D03*
X538038Y488323D03*
X533038D03*
X543280Y491040D03*
X530438Y529525D03*
X541538Y529625D03*
X534401Y529562D03*
X528138Y539925D03*
X540701Y590162D03*
X527638Y590325D03*
X535776Y590487D03*
X530338Y590325D03*
X529408Y603485D03*
X540540Y601008D03*
X538828Y602945D03*
X542848Y602975D03*
X535048Y602885D03*
X541980Y620227D03*
X527828Y615387D03*
X532420Y615484D03*
X539471Y632476D03*
X530779Y637354D03*
X532479Y633588D03*
X541440Y647594D03*
X531970Y650491D03*
X542424Y654821D03*
X536557Y655498D03*
X539120Y670129D03*
X529525Y669349D03*
X529899Y661020D03*
X539734Y675020D03*
X539830Y667332D03*
X531599Y689838D03*
X533270Y679351D03*
X531597Y697509D03*
X535272Y711217D03*
X535062Y708679D03*
X530012Y708618D03*
X543193Y710787D03*
X539577Y721891D03*
X537503Y710088D03*
X528388Y722903D03*
X540062Y708779D03*
X532940Y734810D03*
X531029Y733142D03*
X539650Y780942D03*
X529300Y771341D03*
X533600Y778780D03*
X555938Y97292D03*
X551454Y97154D03*
X547480Y96632D03*
X557995Y110244D03*
X546306Y110193D03*
X550490Y112989D03*
X552173Y138528D03*
X550599Y132596D03*
X550550Y151682D03*
X558059Y154254D03*
X558348Y142511D03*
X551464Y143862D03*
X550604Y168072D03*
X550370Y157461D03*
X557668Y176534D03*
X555510Y173872D03*
X551395Y174172D03*
X555836Y179259D03*
X546000Y180000D03*
X544500Y197500D03*
X546000Y192000D03*
X549909Y207060D03*
X557909Y207537D03*
X555750Y212029D03*
X544500Y207000D03*
X545424Y226722D03*
X546690Y233066D03*
X544990Y231086D03*
X549488Y233003D03*
X549358Y230153D03*
X552120Y232388D03*
X552050Y229124D03*
X550040Y243929D03*
X545703Y245725D03*
X545981Y236287D03*
X550090Y247079D03*
X545116Y266847D03*
X547929Y258102D03*
X557207Y274828D03*
X551341Y274262D03*
X545223Y276895D03*
X557207Y280328D03*
X555072Y289563D03*
X557222Y285109D03*
X553690Y340829D03*
X547340Y339103D03*
X552090Y388953D03*
X548470Y378127D03*
X549760Y407251D03*
X553230D03*
X553750Y410420D03*
X544500Y422583D03*
X557017Y438968D03*
X549574Y432582D03*
X555140Y445940D03*
X546384Y445107D03*
X547488Y452373D03*
X554550Y469674D03*
X545513Y469740D03*
X543338Y459323D03*
X547638Y462356D03*
X546038Y457523D03*
X546250Y490302D03*
X544370Y510267D03*
Y515267D03*
X554860Y531701D03*
X549920Y527242D03*
X551161Y547148D03*
X545138Y539725D03*
X551538Y540325D03*
X551338Y544225D03*
Y551100D03*
X551438Y563825D03*
X551238Y571725D03*
X547000Y590163D03*
X551238Y584025D03*
X543850Y590313D03*
X550149Y604639D03*
X543400Y625963D03*
X552350Y614028D03*
X558281Y637840D03*
X551030Y637200D03*
X543400Y635615D03*
X549314Y647594D03*
X551230Y652844D03*
X555356Y665156D03*
Y669156D03*
X555308Y673156D03*
X551283Y670800D03*
X555357Y689156D03*
X555284Y685156D03*
X555235Y681156D03*
X555308Y677156D03*
X551283Y699243D03*
X555150Y697156D03*
X555271Y693156D03*
X547542Y711523D03*
X544934Y720820D03*
X550535Y721903D03*
X555551Y722342D03*
X557488Y713709D03*
X553725Y717251D03*
X550004Y709559D03*
X555062Y708679D03*
X545062D03*
X553193Y724847D03*
X546566Y724119D03*
X544082Y724460D03*
X549049Y724412D03*
X557426Y724436D03*
X557978Y734053D03*
X545300Y783152D03*
X550940Y771858D03*
X554870Y779438D03*
X566090Y109136D03*
X560938Y97195D03*
X569559Y103123D03*
X565938Y96820D03*
X563230Y150222D03*
X564076Y145372D03*
X563410Y165289D03*
X563274Y162169D03*
X562195Y159015D03*
X563129Y178369D03*
X559646Y174476D03*
X569682Y195199D03*
X572782D03*
X569874Y231795D03*
X572690Y226569D03*
X572020Y222393D03*
X567980Y222353D03*
X568410Y226647D03*
X561258Y230153D03*
X566248Y230283D03*
X563506Y232027D03*
X564274Y279395D03*
X566774Y275195D03*
X566876Y289890D03*
X561525Y298192D03*
X560865Y285434D03*
X565953Y301635D03*
X565310Y412700D03*
X565977Y456156D03*
X566059Y460956D03*
X572440Y464323D03*
Y469323D03*
X562340Y484252D03*
X573840Y512108D03*
X564370Y504117D03*
Y509117D03*
X567493Y532225D03*
X562308Y536895D03*
X566298Y548465D03*
X563188Y541925D03*
X566338Y554235D03*
X561174Y564471D03*
X565858Y576195D03*
X561198Y581793D03*
X566378Y567725D03*
X561608Y571775D03*
X565398Y584765D03*
X568163Y595115D03*
X561568Y589355D03*
X574071Y606204D03*
X568930Y607754D03*
X566053Y627509D03*
X571650Y625998D03*
X574730Y625521D03*
X565647Y637705D03*
X565556Y632431D03*
X571790Y646799D03*
X559440Y650767D03*
X566950Y659439D03*
X563850Y659575D03*
X563840Y653515D03*
X565168Y664614D03*
Y674614D03*
Y669614D03*
X563586Y682137D03*
X563577Y692284D03*
X563441Y676872D03*
X565168Y679614D03*
X563393Y686908D03*
X565168Y689614D03*
Y694614D03*
Y699614D03*
X560544Y718091D03*
X569604Y721248D03*
X574190Y717805D03*
X564319Y721587D03*
X562540Y713454D03*
X560062Y708679D03*
X570614Y713237D03*
X565062Y708679D03*
X571232Y732545D03*
X566798Y734023D03*
X569680Y771106D03*
X560150Y781347D03*
X562700Y772391D03*
X572720Y777184D03*
X588943Y98963D03*
X589308Y103990D03*
X580501Y138336D03*
X583829Y132232D03*
X583547Y128232D03*
X587968Y138765D03*
X581565Y154969D03*
X583970Y144589D03*
X580180Y148894D03*
X579540Y143304D03*
X579897Y161355D03*
X582792Y167632D03*
X581915Y179955D03*
X585580Y210516D03*
X583707Y220762D03*
X587707Y220728D03*
X579707Y229395D03*
X585579Y230095D03*
X576105Y231626D03*
X581474Y274795D03*
X575880Y293016D03*
X575908Y295606D03*
X588607Y305034D03*
X576650Y311446D03*
X581650D03*
X585984Y323246D03*
X579788Y354743D03*
X589070Y423525D03*
X578830Y448192D03*
X588153Y459599D03*
X578840Y512108D03*
X583890Y537093D03*
X576208Y542405D03*
X575838Y548935D03*
X588540Y557418D03*
X584413Y563198D03*
X583538Y552225D03*
X575038Y554725D03*
X575138Y559825D03*
X577778Y556355D03*
X578110Y582149D03*
X582023Y571242D03*
X578399Y585696D03*
X588780Y611056D03*
X586810Y603344D03*
X577000Y620029D03*
X585500Y620926D03*
X588780Y616056D03*
X588950Y650070D03*
X583930Y652439D03*
X579020Y658250D03*
X577217Y652002D03*
X576987Y660180D03*
X580740Y653286D03*
X580637Y663629D03*
X576846Y675985D03*
X579076Y669603D03*
X576520Y667750D03*
X589050Y680160D03*
X579980Y683140D03*
X576644Y679562D03*
X578030Y690236D03*
X577010Y682718D03*
X576519Y687665D03*
X589500Y690546D03*
X579151Y707857D03*
X588151D03*
X584101Y707893D03*
X576442Y705492D03*
X585400Y697289D03*
X584312Y710716D03*
X579220Y720776D03*
X585693Y722428D03*
X583440Y724927D03*
X577570Y734118D03*
X580510Y724421D03*
X587170Y773768D03*
X579240Y775147D03*
X603158Y91535D03*
X601374Y94048D03*
X604543Y94886D03*
X598123Y102023D03*
X595318Y98854D03*
X593850Y103755D03*
X592392Y100623D03*
X595345Y120216D03*
X605070Y123991D03*
X600118Y112568D03*
X592938Y117657D03*
X595438Y138130D03*
X592938Y140689D03*
Y133232D03*
X594938Y127893D03*
X593537Y161023D03*
X592917Y171906D03*
X593277Y179955D03*
X591707Y221095D03*
Y230162D03*
X595374Y236795D03*
X592858Y247079D03*
X593459Y240780D03*
X594067Y265168D03*
X594174Y256695D03*
X593874Y262395D03*
X590874Y275195D03*
X594374Y271395D03*
X596574Y276393D03*
X593607Y305034D03*
X590984Y323246D03*
X598551Y329541D03*
X601450Y326509D03*
X604338Y338285D03*
X600770Y358702D03*
X597440Y391690D03*
X594860Y395088D03*
X600680Y412780D03*
X590720Y456076D03*
X591100Y450128D03*
X605800Y463167D03*
X603819Y485332D03*
X598670Y508170D03*
X603010Y527908D03*
X596560Y536108D03*
X606300Y551844D03*
X604820Y555040D03*
X604437Y557956D03*
X596050Y557563D03*
X592437Y566543D03*
X601043Y567781D03*
X605396Y590552D03*
X605286Y584152D03*
X605290Y594166D03*
X596401Y589852D03*
X593867Y595695D03*
X602314Y607641D03*
Y602641D03*
X593867Y600695D03*
X605010Y641435D03*
X600980Y641533D03*
X591279Y656223D03*
X596998Y658008D03*
X591840Y659568D03*
X596470Y655231D03*
X602332Y671156D03*
X600736Y668425D03*
X593142Y663828D03*
X600719Y675156D03*
X597300Y663128D03*
X600690Y691896D03*
X600727Y681876D03*
X602020Y679156D03*
X600727Y686876D03*
X604220Y703774D03*
X600650Y707835D03*
X592960Y703291D03*
X601856Y711479D03*
X606146Y713145D03*
X601813Y715579D03*
X598880Y719232D03*
X595950Y708997D03*
X594170Y719290D03*
X603938Y753623D03*
X606270Y774615D03*
X597530Y780191D03*
X592480Y771514D03*
X610543Y107678D03*
X617925Y114064D03*
X613432Y153528D03*
X610415Y237441D03*
X617778Y238873D03*
X612974Y269095D03*
X609150Y328514D03*
X616490Y327534D03*
X607671Y344818D03*
X619190Y336986D03*
X608306Y359971D03*
X611848Y359784D03*
X607855Y352341D03*
X618581Y354818D03*
X617592Y362539D03*
X620238Y364369D03*
X609078Y388557D03*
X619014Y408353D03*
X609078Y393557D03*
X612641Y397478D03*
Y402478D03*
X611050Y423087D03*
X621399Y420400D03*
X611130Y417928D03*
X616258Y422211D03*
X610580Y448662D03*
X609370Y452974D03*
X610010Y456581D03*
X617980Y460408D03*
X613470Y537495D03*
X616320Y537066D03*
X610070Y557588D03*
X621937Y558276D03*
X621840Y555040D03*
X609060Y552101D03*
X610821Y566494D03*
X621937Y567143D03*
X609026Y579132D03*
X617270Y580443D03*
X611520Y596594D03*
X612270Y586543D03*
X612493Y607666D03*
X611254Y617943D03*
X612370Y614143D03*
X615690Y625536D03*
X616730Y633290D03*
X608310Y641603D03*
X611572Y629894D03*
X620510Y639427D03*
X616471Y636215D03*
X613796Y648705D03*
X612950Y656140D03*
X607620Y647169D03*
X615700Y657757D03*
X613200Y661577D03*
X620160Y670594D03*
X615940Y666862D03*
X610693Y679333D03*
X610570Y691156D03*
X610550Y686640D03*
X610810Y683933D03*
X612670Y681438D03*
X612811Y688422D03*
X608975Y708094D03*
X612914Y707630D03*
X610540Y697964D03*
X618020Y700000D03*
X610570Y695156D03*
X607380Y699671D03*
X617930Y703520D03*
X620480Y693827D03*
X609070Y721917D03*
X616070Y720838D03*
X613730Y717663D03*
X620670Y722216D03*
X620830Y717516D03*
X609840Y713617D03*
X619080Y772610D03*
X619030Y778682D03*
X612260Y783106D03*
X609347Y778624D03*
X626380Y85117D03*
X624020Y83243D03*
X623750Y87130D03*
X626380Y88518D03*
X623725Y90422D03*
X626180Y91919D03*
X623820Y93654D03*
X626320Y96084D03*
X623610Y97125D03*
X626180Y99276D03*
X628838Y120216D03*
X628738Y133012D03*
X624800Y184953D03*
Y179953D03*
X634962Y200121D03*
Y195121D03*
X622470Y261628D03*
X635000Y265400D03*
X634212Y281670D03*
X624383Y292591D03*
X631672Y301066D03*
X632376Y305257D03*
X631702Y307880D03*
X632122Y312898D03*
X633773Y310439D03*
X635652Y313118D03*
X636962Y310928D03*
X623820Y321062D03*
X633470Y326710D03*
X628140Y317610D03*
X631860Y321455D03*
X627000Y327926D03*
X622890Y325227D03*
X633652Y315198D03*
X628141Y344818D03*
X630190Y336986D03*
X625190D03*
X624889Y357778D03*
X637738Y392034D03*
X636990Y386464D03*
X627022Y383713D03*
X634511Y389156D03*
X637614Y397259D03*
X630691Y405007D03*
X636938Y402885D03*
X630691Y410007D03*
X636586Y410910D03*
X633455Y427209D03*
X634578Y424964D03*
X635840Y449890D03*
X626250Y450248D03*
X631280Y446007D03*
X635120Y456136D03*
X630570Y451450D03*
X622100Y465822D03*
X625900Y461769D03*
X628250Y471142D03*
X632680Y466669D03*
X636010Y469995D03*
X630420Y491511D03*
X636170Y493028D03*
X622600Y488753D03*
X632157Y511230D03*
X625130Y534199D03*
X634530Y521565D03*
X622798Y546764D03*
X636890Y571351D03*
X624870Y573143D03*
X627084Y578257D03*
X634921Y580163D03*
X627047Y581066D03*
X623940Y628720D03*
X636890Y627095D03*
X629781Y628559D03*
X627986Y625895D03*
X630984Y624829D03*
X622510Y635544D03*
X634137Y631342D03*
X627146Y638932D03*
X623290Y641222D03*
X634137Y639352D03*
X630137Y639312D03*
X631930Y655254D03*
X633970Y723033D03*
X622290Y708516D03*
X628160Y722343D03*
X631690Y733744D03*
X635460Y735130D03*
X636170Y729335D03*
X630040Y745114D03*
X632300Y749755D03*
X636910Y745815D03*
X624010Y746351D03*
X629912Y769200D03*
X625010Y778281D03*
X636390Y775395D03*
X632030Y779137D03*
X632000Y775400D03*
X643957Y53688D03*
X639957Y53849D03*
X639200Y170100D03*
X639350Y250123D03*
X642932Y284768D03*
X640112Y285042D03*
X649995Y296433D03*
X652362Y306598D03*
X640647Y339854D03*
X648450Y338711D03*
X648838Y349785D03*
X642863Y358010D03*
X639838Y349818D03*
X646171Y364676D03*
X648425Y373474D03*
X652139Y377125D03*
X641236Y381616D03*
X645236Y377858D03*
X648493Y417221D03*
X648208Y427819D03*
X643208D03*
X653070Y427500D03*
X650822Y425295D03*
X641690Y443656D03*
X647280Y446851D03*
X653360Y446280D03*
X651080Y455238D03*
X652110Y465238D03*
X651840Y460012D03*
X648920Y457851D03*
X646600Y463571D03*
X648956Y469323D03*
X650521Y482930D03*
X647921Y475778D03*
X651395Y487265D03*
X650790Y497730D03*
X650150Y494337D03*
X638350Y507893D03*
X641842Y516730D03*
X646460Y512967D03*
X652690Y531693D03*
X640470Y523266D03*
X645040Y524444D03*
X645150Y535704D03*
X639673Y576888D03*
X651437Y578943D03*
X646732Y580781D03*
X641870Y580743D03*
X646870Y569443D03*
Y576243D03*
X644636Y627257D03*
X642795Y624818D03*
X648701Y624774D03*
X646940Y643448D03*
X641263Y631393D03*
X649173Y629876D03*
X646737Y639413D03*
X642737D03*
X647870Y649784D03*
X646580Y654775D03*
X651226Y666288D03*
X639940Y687841D03*
X640330Y684439D03*
X642999Y685781D03*
X644950Y719110D03*
X638890Y734879D03*
X652660Y749000D03*
X639920Y753526D03*
X646680Y755009D03*
X646500Y746300D03*
X650400Y770522D03*
X638470Y762212D03*
X649640Y757527D03*
X646370Y759252D03*
X647410Y767053D03*
X651690Y778099D03*
X640010Y778215D03*
X652212Y786700D03*
X655947Y53677D03*
X659947Y53722D03*
X655642Y144915D03*
Y149915D03*
X655695Y159567D03*
Y164567D03*
X655030Y228744D03*
Y223744D03*
X657838Y243407D03*
Y238407D03*
X656270Y299379D03*
X654962Y307698D03*
X654060Y302459D03*
X659350Y298810D03*
X655122Y315070D03*
X656730Y338633D03*
X659543Y377086D03*
X662390Y377039D03*
X653938Y364885D03*
X668925Y364887D03*
X663632Y366698D03*
X669215Y377488D03*
X658295Y417662D03*
X653649Y417582D03*
X668779Y417135D03*
X663674Y417999D03*
X655812Y424106D03*
X663339Y425601D03*
X658339D03*
X664450Y435739D03*
X658680Y446610D03*
X660458Y470932D03*
X659828Y465162D03*
X667774Y477992D03*
X661158Y486152D03*
X667070Y483608D03*
X662780Y477039D03*
X660518Y492862D03*
X662630Y500823D03*
X654240Y511568D03*
X653800Y505331D03*
X659933Y513927D03*
X664024Y513414D03*
X668573Y514155D03*
X668823Y532470D03*
X668627Y527718D03*
X667050Y535324D03*
X655445Y591918D03*
X658980Y610043D03*
X655978Y609635D03*
X656070Y612743D03*
X655688Y601761D03*
X663560Y625019D03*
X659600Y623785D03*
X655873Y615540D03*
X654221Y631425D03*
X657550Y655072D03*
X659978Y666274D03*
X665050Y680648D03*
X657340Y690286D03*
X655610Y706309D03*
X656505Y701191D03*
X657320Y723584D03*
X654050Y718086D03*
X656650Y713057D03*
X659200Y721454D03*
X659300Y734119D03*
X654000Y736400D03*
X655574Y728674D03*
X657570Y730414D03*
X658860Y727383D03*
X656000Y732400D03*
X657500Y761500D03*
X664460Y785890D03*
X657010Y786039D03*
X675927Y53779D03*
X669987Y53672D03*
X676590Y188198D03*
X680100Y188182D03*
X680220Y200725D03*
X678650Y203480D03*
X681770Y203514D03*
X682140Y191214D03*
Y194615D03*
X680310Y217357D03*
X678750Y214908D03*
X681870Y214942D03*
X679590Y352829D03*
X679430Y350013D03*
X677083Y375124D03*
X677946Y387211D03*
X678986Y392661D03*
X679138Y397985D03*
X680017Y403143D03*
X678838Y407785D03*
X673368Y416621D03*
X671056Y426300D03*
X672660Y441007D03*
X673740Y449887D03*
X682764Y444832D03*
X677070Y444820D03*
X672190Y457216D03*
X683112Y479786D03*
X679299Y491473D03*
X684876Y497385D03*
X674156Y503662D03*
X678450Y508438D03*
X680790Y504521D03*
X677160Y529422D03*
X675044Y524581D03*
X684620Y535923D03*
X678217Y536752D03*
X678360Y557426D03*
X673950Y557314D03*
X677850Y562515D03*
X673700D03*
X677730Y567706D03*
X673590Y567696D03*
X670940Y612070D03*
X683720Y631732D03*
X678386Y668420D03*
X673386D03*
X675100Y749300D03*
X672710Y746235D03*
X672500Y749179D03*
X684500Y786665D03*
X676390Y778439D03*
X677490Y782114D03*
X673290Y782855D03*
X677227Y786454D03*
X669320Y783845D03*
X681480Y777388D03*
X681164Y783461D03*
X669810Y786721D03*
X672500Y779579D03*
X683520Y789080D03*
Y792080D03*
X698150Y136791D03*
X687546Y154228D03*
X699990Y149631D03*
X700060Y144981D03*
X693520Y186376D03*
X697850Y186441D03*
X689820Y200159D03*
Y203491D03*
X689480Y191144D03*
Y194615D03*
X691970Y216820D03*
X691690Y212100D03*
X693540Y205721D03*
X697800Y205879D03*
X692010Y221158D03*
X687584Y233034D03*
X686686Y392522D03*
X687869Y386780D03*
X688118Y381043D03*
X686686Y397522D03*
X689527Y407843D03*
X685859Y403970D03*
X691037Y401739D03*
X689527Y412843D03*
X687130Y464132D03*
X691070Y464058D03*
X689017Y497282D03*
X694823Y498932D03*
X692520Y506898D03*
X696494Y513677D03*
X689729Y509580D03*
X696891Y507279D03*
X700719Y516954D03*
X686661Y519199D03*
X698438Y524890D03*
X686770Y543325D03*
X694150Y536155D03*
X690040Y535797D03*
X687183Y539585D03*
X687660Y631799D03*
X685640Y634154D03*
X698386Y667241D03*
X693386D03*
X699600Y776000D03*
X689700Y774500D03*
X711676Y51019D03*
X701770Y331938D03*
X702730Y455483D03*
X704550Y444407D03*
X715528Y459332D03*
X710768Y475972D03*
X715328Y481122D03*
X704766Y498880D03*
X713978Y498075D03*
X716021Y516945D03*
X700829Y504041D03*
X707736Y510140D03*
X707920Y505575D03*
X706361Y532632D03*
X716260Y525295D03*
X712820Y519647D03*
X701170Y538508D03*
X708258Y549815D03*
X713300Y578995D03*
X713190Y583032D03*
X712740Y593101D03*
X712732Y631749D03*
X716064D03*
X713742Y634373D03*
X708386Y669774D03*
X703386D03*
X713445Y677641D03*
X709500Y736800D03*
X704000Y770800D03*
X716245Y765576D03*
X719800Y24920D03*
X726500Y123466D03*
X726400Y130303D03*
X726470Y126659D03*
X726580Y455637D03*
X731570Y464043D03*
X726430Y465371D03*
X726830Y460815D03*
X727940Y469943D03*
X731340Y476723D03*
X720140Y478333D03*
X718431Y483368D03*
X721290Y484381D03*
X719370Y472436D03*
X725730Y486788D03*
X729640Y486848D03*
X727602Y500100D03*
X720150Y491632D03*
X719332Y515757D03*
X719761Y532432D03*
X728661Y558934D03*
X731251Y558975D03*
X726154Y559002D03*
X720445Y558990D03*
X723370Y558906D03*
X719092Y631682D03*
X717372Y634474D03*
X727830Y641829D03*
X728690Y649829D03*
X721100Y689400D03*
X718445Y677641D03*
X731200Y716200D03*
X730800Y728400D03*
X729500Y746300D03*
X721245Y765576D03*
X726925Y778490D03*
X731925D03*
X744760Y103711D03*
X744790Y106938D03*
X747710Y100293D03*
X738370Y123395D03*
X745070Y110183D03*
X738270Y130232D03*
X738340Y126588D03*
X747080Y129815D03*
X747600Y323527D03*
X745220Y327250D03*
X736310Y450774D03*
X737350Y464330D03*
Y459823D03*
X743364Y478975D03*
X743150Y483502D03*
X738130Y502748D03*
X732817Y489435D03*
X734575Y492575D03*
X745500Y492500D03*
X744020Y566143D03*
X744090Y575066D03*
X743951Y578833D03*
X744050Y571834D03*
X747470Y585542D03*
X747460Y582318D03*
X744000Y647919D03*
X733210Y645829D03*
X732540Y653829D03*
X751080Y100293D03*
X754580Y124020D03*
X748070Y110209D03*
X751180D03*
X754610Y127247D03*
X750930Y129815D03*
X750430Y314330D03*
X750350Y311343D03*
X750700Y323771D03*
X753230Y328262D03*
X759400Y334839D03*
X754850Y335055D03*
X755500Y337791D03*
X758494Y455532D03*
X748723Y455332D03*
X758500Y469500D03*
X751730Y583047D03*
X765250Y357789D03*
X765610Y361194D03*
G54D17*
X20859Y109561D03*
X78740Y30708D03*
X73740Y20708D03*
X713661D03*
X708661Y30708D03*
X703661Y20708D03*
X712975Y155655D03*
Y165455D03*
Y173455D03*
Y234461D03*
Y244261D03*
Y252261D03*
X723275Y155655D03*
Y165455D03*
Y173455D03*
Y234461D03*
Y244261D03*
Y252261D03*
G54D46*
X556181Y81889D03*
G54D11*
X-44872Y125213D03*
Y141213D03*
Y232533D03*
D03*
Y248533D03*
D03*
Y738493D03*
Y754493D03*
X-26872Y125213D03*
Y141213D03*
Y232533D03*
D03*
Y248533D03*
D03*
Y738493D03*
Y754493D03*
G54D21*
X36024Y181225D03*
Y205257D03*
Y199249D03*
Y193241D03*
Y217272D03*
Y211264D03*
X41930Y184229D03*
Y202253D03*
Y190237D03*
Y208260D03*
G54D34*
X154038Y511386D03*
X153967Y517186D03*
X162335Y521906D03*
X155400Y533436D03*
X154246Y527468D03*
X162335Y528206D03*
X159186Y534504D03*
X154945Y539233D03*
X159185Y547103D03*
X154900Y548682D03*
X159186Y553402D03*
X157611Y557468D03*
X154410Y557990D03*
X178818Y274540D03*
X178085Y518755D03*
X168617Y525756D03*
X172371Y519783D03*
X174720Y531356D03*
X178117Y528187D03*
X178099Y550267D03*
X174105Y542290D03*
X167027Y539526D03*
Y536376D03*
X173217Y536556D03*
X181818Y274540D03*
X181232Y515607D03*
X187417Y508756D03*
X189007Y514846D03*
X187875Y534128D03*
X181232Y537654D03*
X184384Y543955D03*
X188927Y537836D03*
X190434Y546870D03*
X207309Y539953D03*
X216184Y268587D03*
X223709Y505353D03*
X214118Y528583D03*
X218751Y543835D03*
X233626Y502591D03*
X230476D03*
X243075D03*
X236776Y518339D03*
X233626Y508891D03*
Y515190D03*
X230476D03*
X233626Y518339D03*
X236776Y512040D03*
X243075Y508891D03*
X230476D03*
X236776Y515190D03*
X230476Y518339D03*
Y512040D03*
X239925Y518339D03*
X233626Y521489D03*
Y527788D03*
X230476Y534087D03*
X236776Y521489D03*
Y527788D03*
Y524639D03*
X230476D03*
X233626Y534087D03*
X239925Y527788D03*
Y524639D03*
X230476Y527788D03*
Y521489D03*
X239925Y534087D03*
Y521489D03*
X233626Y543536D03*
X239925Y540386D03*
Y543536D03*
X236776Y537236D03*
X230476D03*
Y543536D03*
Y540386D03*
X233626D03*
X236776Y543536D03*
X233626Y537236D03*
X239925D03*
X243075Y559284D03*
Y552984D03*
X252524Y502591D03*
X255673D03*
X249374D03*
X246224D03*
X255673Y512040D03*
X252524D03*
X255673Y508891D03*
Y505741D03*
X249374D03*
Y508891D03*
X252524Y505741D03*
Y508891D03*
X249374Y512040D03*
X246224D03*
X252524Y549835D03*
X255673D03*
X249374D03*
X246224Y559284D03*
Y556134D03*
Y562434D03*
X252554Y559314D03*
X262904Y293850D03*
X268943Y291086D03*
X274582Y502591D03*
X271402Y499441D03*
X271429Y496295D03*
X261972Y502591D03*
X268272Y512040D03*
X271422D03*
X265121Y508891D03*
X261972D03*
Y505741D03*
X265122Y512040D03*
X261972D03*
X265122Y505741D03*
X268272Y549836D03*
X271421D03*
X265122D03*
X261972D03*
X271421Y552985D03*
X274572Y556142D03*
X287173Y499445D03*
X277712Y502595D03*
X277725Y534092D03*
Y527792D03*
Y521493D03*
Y540391D03*
Y543541D03*
Y537241D03*
X290322Y549841D03*
X280872D03*
X679175Y464038D03*
X674353Y463842D03*
X683112Y464038D03*
Y483723D03*
X683113Y471941D03*
X683112Y487660D03*
X690986Y467975D03*
X687049Y479786D03*
X690986Y483723D03*
X687049Y471912D03*
X698683Y487517D03*
X690986Y487660D03*
X687049D03*
X692955Y502112D03*
X702797Y464038D03*
Y467975D03*
X706734Y471913D03*
Y483723D03*
X710671Y479786D03*
X706734Y475850D03*
X710671Y471913D03*
X702585Y483749D03*
X702797Y471912D03*
Y479786D03*
X706734D03*
G54D37*
X399606Y377165D03*
X413386Y363385D03*
X403543Y367322D03*
Y387008D03*
X413386Y390945D03*
X427166Y377165D03*
X423229Y367322D03*
Y387008D03*
G54D36*
X354348Y38554D03*
X393718D03*
G54D41*
X507489Y281538D03*
G54D51*
X605796Y204845D03*
X611702Y185690D03*
Y178997D03*
Y200690D03*
Y193997D03*
G54D53*
X711575Y143555D03*
Y195355D03*
Y222361D03*
Y274161D03*
X733975Y143555D03*
Y195355D03*
Y222361D03*
Y274161D03*
G54D48*
X590999Y77041D03*
Y84915D03*
Y92789D03*
X615657Y77041D03*
Y84915D03*
Y92789D03*
G54D44*
X524780Y28803D03*
X514780Y38803D03*
X524780D03*
X534780Y28803D03*
X544780D03*
X534780Y38803D03*
X544780D03*
X554780D03*
X587371Y28803D03*
X577371Y38803D03*
X587371D03*
X597371Y28803D03*
X607371D03*
X597371Y38803D03*
X607371D03*
X617371D03*
X639963D03*
X649963Y28803D03*
Y38803D03*
X659963Y28803D03*
X669963D03*
X659963Y38803D03*
X669963D03*
X679963D03*
G54D26*
X65900Y566403D03*
X66181Y562149D03*
X63930Y560181D03*
X66262Y553344D03*
X65989Y578115D03*
X66036Y574901D03*
X63670Y576040D03*
X69766Y582525D03*
X81491Y533191D03*
X80318Y544311D03*
X81585Y536382D03*
X80318Y541026D03*
X112386Y71874D03*
X114072Y480964D03*
X110400Y502223D03*
X110436Y499681D03*
X110472Y496888D03*
X113337Y502080D03*
X113372Y496888D03*
X113301Y499574D03*
X112575Y532934D03*
X113912Y541144D03*
X114005Y544358D03*
X112627Y536697D03*
X130350Y130400D03*
Y134167D03*
X126072Y480864D03*
X122018Y516353D03*
X135640Y134167D03*
X135590Y130449D03*
X139365Y516636D03*
X139402Y513707D03*
X299629Y623877D03*
X318968Y536052D03*
X319135Y591407D03*
X336088Y454511D03*
X325040Y480129D03*
X355150Y486758D03*
X368787Y472998D03*
X374203Y482079D03*
X377284Y473374D03*
X399060Y454322D03*
X399050Y450968D03*
X398800Y462248D03*
Y458058D03*
X405878Y294071D03*
X403130Y418091D03*
X406200Y417755D03*
X405980Y414630D03*
X405930Y411386D03*
X406140Y424766D03*
X406150Y433203D03*
X406530Y440667D03*
X406000Y444755D03*
X402900Y444842D03*
X413733Y490781D03*
X410733D03*
X407733D03*
Y493781D03*
Y496781D03*
Y499781D03*
X410733Y493781D03*
X413733D03*
X410733Y496781D03*
X413733D03*
X410733Y499781D03*
X413733D03*
X402499Y554143D03*
X418597Y273538D03*
X418698Y279631D03*
X418998Y289871D03*
X418718Y301181D03*
X423278Y525160D03*
X428874Y525193D03*
X417520Y525128D03*
X428874Y530627D03*
X417520Y531177D03*
X428745Y536999D03*
X423332Y536763D03*
X417617Y536773D03*
X454263Y77675D03*
X450917Y97566D03*
X452669Y157140D03*
X539438Y250323D03*
X589036Y548825D03*
X596530Y574903D03*
X596495Y578903D03*
X596484Y582903D03*
X596209Y586903D03*
X590898Y597158D03*
X590842Y608112D03*
X591023Y600384D03*
X605362Y609413D03*
X590646Y618751D03*
X609168Y554851D03*
X607077Y566915D03*
X632362Y565543D03*
X636868Y593141D03*
X630768Y593241D03*
X624468D03*
Y612141D03*
X624368Y605941D03*
Y599741D03*
X629868Y612241D03*
X635968D03*
X643012Y565243D03*
X651437Y569676D03*
X643568Y593241D03*
Y612341D03*
Y606641D03*
Y599541D03*
X638470Y639290D03*
X650928D03*
X665170Y595943D03*
X661396Y588900D03*
X664603Y601976D03*
X654645Y627064D03*
X667610Y617197D03*
X655170Y639432D03*
X681310Y666671D03*
X671400Y666151D03*
X685410Y621250D03*
X688340Y621294D03*
X692720Y670540D03*
X698830Y670652D03*
X703570Y673036D03*
X707660Y673204D03*
X713910Y681330D03*
X718510Y681526D03*
X718150Y763015D03*
X721100Y762903D03*
X727570Y775278D03*
X730990Y775334D03*
G54D32*
X130794Y493910D03*
X133731D03*
X128240Y666583D03*
X120909Y674490D03*
X141682Y269829D03*
X150787Y9246D03*
X158181Y11978D03*
X163518Y243987D03*
X162317Y249877D03*
X161918Y254287D03*
X162484Y276599D03*
X161767Y287242D03*
X162181Y303075D03*
X161687Y310355D03*
X162063Y327940D03*
X159564Y328013D03*
X161513Y317143D03*
X159285Y336220D03*
X164418Y348187D03*
X171310Y12450D03*
X180510Y233307D03*
X174138Y243873D03*
X167467Y243242D03*
X171668Y256287D03*
X175118Y274287D03*
X170617Y267326D03*
X175318Y278687D03*
X170510Y275522D03*
X177470Y294933D03*
X180254Y295023D03*
X175162Y293934D03*
X175659Y286984D03*
X176037Y309845D03*
X180254Y310663D03*
X178812Y324259D03*
X180342Y316469D03*
X175330Y318552D03*
X177359Y332553D03*
X174876Y336549D03*
X168110Y350642D03*
X178232Y430642D03*
X178217Y435317D03*
X193677Y243855D03*
X184318Y247612D03*
X194056Y256697D03*
X193735Y265857D03*
X188442Y252643D03*
X184829Y259139D03*
X190918Y277687D03*
X185991Y279041D03*
X186118Y270787D03*
X183698Y285693D03*
X193557Y294428D03*
X187812Y286352D03*
X184812Y292979D03*
X186254Y295023D03*
X194771Y302176D03*
X193812Y308619D03*
X195254Y310663D03*
X184754Y302843D03*
X193313Y325492D03*
X186296Y326366D03*
X192293Y340792D03*
X185195Y332852D03*
X184367Y337792D03*
X192519Y352761D03*
X182877Y430662D03*
X182879Y435312D03*
X212020Y234359D03*
X211935Y244085D03*
X198685Y240785D03*
X211028Y255696D03*
X210333Y265197D03*
X208129Y257519D03*
X206144Y252477D03*
X208289Y263639D03*
X208226Y269697D03*
X201667Y274542D03*
X199509Y278094D03*
X206299Y312598D03*
X209300Y322800D03*
X207310Y330149D03*
X208485Y332356D03*
X200905Y333776D03*
X201489Y336207D03*
Y339107D03*
X198987Y353137D03*
X206657Y356116D03*
X217135Y244085D03*
X219772Y252659D03*
X215761Y252833D03*
X224794Y256754D03*
X218153Y260697D03*
Y263697D03*
X223929Y263639D03*
X225199Y281098D03*
X216109Y274139D03*
X212599Y281098D03*
Y290548D03*
X225199Y287398D03*
X212599Y293698D03*
X222049Y290548D03*
X225199Y309448D03*
Y299998D03*
Y303148D03*
X222049Y309448D03*
X212599Y299998D03*
Y303148D03*
X222049Y312598D03*
X218899Y309448D03*
X222049Y303148D03*
X215100Y322700D03*
X217129Y327207D03*
X215085Y325649D03*
X212600Y319100D03*
X217129Y324207D03*
Y336207D03*
X217067Y339542D03*
X217129Y333207D03*
X223010Y344242D03*
X228057Y352837D03*
X222777Y353066D03*
X214888Y352909D03*
X231749Y265139D03*
X239569Y257639D03*
X240910Y274742D03*
X233793Y269697D03*
X237799Y290548D03*
Y284248D03*
X231499Y287398D03*
X237800Y299998D03*
X231499Y309448D03*
X241258Y319123D03*
X240692Y344204D03*
X233055Y339936D03*
X230725Y331649D03*
X238084Y355992D03*
X259030Y123727D03*
X259443Y120773D03*
X255209Y260639D03*
X255359Y266557D03*
X257046Y279607D03*
X255205Y272755D03*
X244109Y277996D03*
X250399Y290548D03*
X244099Y284248D03*
X250399D03*
X244099Y293698D03*
X254334Y298728D03*
X247249Y303148D03*
X244118Y309387D03*
X247281Y315727D03*
X248509Y339207D03*
X247218Y333049D03*
X255009Y338318D03*
X259444Y354291D03*
X246265Y355855D03*
X249541Y587156D03*
Y583156D03*
X246639Y608378D03*
Y605778D03*
X249640Y602519D03*
X246639Y624378D03*
Y621778D03*
Y616378D03*
Y613778D03*
X273660Y23037D03*
X273645Y27712D03*
X269620Y243240D03*
X263029Y259139D03*
X265073Y266697D03*
X263029Y265139D03*
X271811Y256687D03*
X271898Y263173D03*
X271944Y278363D03*
X264386Y280407D03*
X265944Y278363D03*
X274886Y272587D03*
X273386Y280407D03*
X270444Y270543D03*
X271886Y272587D03*
X268886D03*
X268944Y278363D03*
X262886Y288227D03*
X264386Y296047D03*
X271811Y303313D03*
X271944Y309643D03*
X262944D03*
X261386Y311687D03*
X262035Y322679D03*
X267883Y325837D03*
X268502Y344181D03*
X263576Y340898D03*
X274701Y333804D03*
X270326Y335795D03*
X269117Y352876D03*
X278305Y23057D03*
X278307Y27707D03*
X278354Y244281D03*
X290154Y244007D03*
X285934Y243931D03*
X282178Y244005D03*
X289254Y255688D03*
X286492Y258364D03*
X283660Y251542D03*
X281954Y255588D03*
X288954Y260788D03*
X276328Y264687D03*
X277886Y272587D03*
X280886D03*
X286010Y276042D03*
X282867Y281142D03*
X279386Y311687D03*
X285890Y311357D03*
X281461Y321744D03*
X280776Y326412D03*
X275660Y338857D03*
X281212Y338079D03*
X290190Y352480D03*
X278943Y346914D03*
X277718Y352687D03*
X282818D03*
X286711Y352668D03*
X283140Y346082D03*
X291066Y590488D03*
Y593088D03*
X300118Y250987D03*
X295910Y266706D03*
X295110Y262961D03*
X295307Y275439D03*
X294510Y280709D03*
X297782Y291966D03*
X295010Y286767D03*
X294888Y304456D03*
X294781Y309788D03*
X295200Y321473D03*
X294596Y328129D03*
X294218Y343587D03*
X294888Y335326D03*
X294618Y348287D03*
X293467Y352442D03*
X299121Y597542D03*
X311420Y250230D03*
X315410Y258656D03*
X313888Y566003D03*
X313141Y550821D03*
X313075Y553755D03*
X313108Y556556D03*
X313275Y559590D03*
X316788Y572903D03*
X316688Y569603D03*
X320367Y618071D03*
X314910Y627222D03*
X317722Y614646D03*
X329260Y603381D03*
X328930Y611691D03*
X383344Y590662D03*
Y593262D03*
X391630Y597900D03*
X410522Y593947D03*
X413022D03*
X412960Y618207D03*
X410315Y614782D03*
X624101Y296525D03*
X640448Y294422D03*
X643170Y294282D03*
X641227Y297070D03*
X644113Y297071D03*
X653352Y291388D03*
X640171Y311965D03*
X644105D03*
X651352Y323938D03*
X653162Y318398D03*
X650162D03*
X638166Y560972D03*
X638286Y557415D03*
X660899Y311515D03*
X654352Y323938D03*
X664870Y614543D03*
X656971Y660492D03*
X671129Y305579D03*
X671166Y302550D03*
X687049Y467975D03*
X698860D03*
Y471912D03*
X690986D03*
Y479786D03*
X687049Y483723D03*
X698860Y479786D03*
Y483723D03*
X752960Y653967D03*
X749520Y658372D03*
G54D38*
X414961Y98622D03*
G54D19*
X23628Y321764D03*
Y338300D03*
X434102Y232640D03*
Y311875D03*
X583913Y69167D03*
X608571D03*
G54D22*
X40749Y150808D03*
Y249194D03*
G54D28*
X76880Y143269D03*
X739968Y29361D03*
G54D33*
X151969Y98622D03*
G54D23*
X43898Y168544D03*
Y231457D03*
G54D40*
X481102Y34528D03*
G54D52*
X688977Y105315D03*
Y719488D03*
G54D30*
X98426Y105512D03*
Y719685D03*
G54D54*
X712975Y183255D03*
Y262061D03*
X723275Y183255D03*
Y262061D03*
G54D27*
X83740Y20708D03*
G54D47*
X590999Y69167D03*
X615657D03*
G54D20*
X36024Y187233D03*
X41930Y178221D03*
Y196245D03*
Y220276D03*
Y214268D03*
G54D29*
X86880Y143269D03*
X749968Y29361D03*
G54D18*
X25439Y303260D03*
Y356804D03*
G54D31*
X102362Y247244D03*
Y349606D03*
X354331Y247244D03*
Y349606D03*
G54D39*
X413386Y377165D03*
G54D25*
X66981Y59390D03*
X62981Y59440D03*
X57040Y73421D03*
X72890Y154349D03*
X81210Y261337D03*
X129860Y14571D03*
X131474Y43439D03*
X137500Y25494D03*
X147461Y38078D03*
X147497Y42983D03*
X145210Y60154D03*
X149157Y60010D03*
X141190Y597685D03*
X145880Y584125D03*
X144710Y598135D03*
X134450Y682978D03*
X134777Y738726D03*
Y734726D03*
X134720Y742382D03*
X153863Y15176D03*
X164139Y13027D03*
X154592Y21173D03*
X152412Y38112D03*
X152366Y42983D03*
X152789Y53124D03*
X161640Y403286D03*
X154307Y507507D03*
X154517Y513931D03*
X159185Y531356D03*
X153731Y520734D03*
X159185Y543953D03*
X155060Y545526D03*
X154945Y542383D03*
Y536083D03*
X162315Y553391D03*
X155109Y561153D03*
X154900Y551832D03*
X151900Y590454D03*
X157963Y643289D03*
X179235Y7369D03*
X171666Y7449D03*
X175280Y12401D03*
X174166Y7449D03*
X166639Y13027D03*
X169149Y50968D03*
X175290Y389582D03*
X174500Y383383D03*
X175993Y414924D03*
X178082Y537654D03*
X171053Y569411D03*
X179532Y600437D03*
X173432D03*
X165832Y600337D03*
Y606037D03*
Y613137D03*
X172532Y619537D03*
X178632Y619437D03*
X165832D03*
X177038Y647135D03*
X166388Y647435D03*
X189235Y7369D03*
X191735D03*
X181735D03*
X190700Y418325D03*
X186417Y518526D03*
X186467Y514036D03*
X184920Y508626D03*
X181232Y528205D03*
Y543953D03*
X184384Y537656D03*
X188383Y556895D03*
X184386Y553406D03*
X185032Y606737D03*
X184932Y600537D03*
X185032Y612937D03*
X184932Y619437D03*
X211760Y610915D03*
X207476Y608936D03*
X207010Y602472D03*
X211862Y617709D03*
X202450Y663633D03*
X216209Y488853D03*
X213209D03*
X224209Y494928D03*
X221591Y563371D03*
X223561Y561475D03*
X218859Y593093D03*
X219296Y604811D03*
X215699Y625977D03*
X215985Y633977D03*
X216107Y637977D03*
X215948Y629977D03*
X231209Y566282D03*
X245609Y517182D03*
X262798Y417886D03*
X267741Y491608D03*
X262009Y556153D03*
X284024Y499445D03*
X303722Y385367D03*
X301209Y488853D03*
X303709Y489353D03*
X307116Y385979D03*
X336057Y575657D03*
X369280Y415600D03*
X374560Y412421D03*
X401670Y93807D03*
X409060Y92095D03*
X468210Y401505D03*
X474130Y553659D03*
X474290Y563565D03*
X486640Y543687D03*
X486720Y563730D03*
X481380Y553210D03*
X481410Y573563D03*
X485890Y590563D03*
X489380Y590839D03*
X582920Y194220D03*
X588692Y192809D03*
X758223Y446532D03*
X757823Y451032D03*
G54D14*
X-35858Y731383D03*
X21881Y595792D03*
X17071Y658951D03*
X33841Y9183D03*
X28104Y30414D03*
X24411Y16186D03*
X34149Y44149D03*
X30282Y34564D03*
X28250Y438740D03*
X37990Y453022D03*
X28250Y472076D03*
X37990Y520218D03*
X38807Y543539D03*
X38349Y555730D03*
X34440Y597285D03*
X36930Y611082D03*
X35862Y617052D03*
X29964Y658951D03*
X45410Y21563D03*
X54860Y16952D03*
X43480Y34592D03*
X45578Y50478D03*
X54703Y122796D03*
X46811Y122928D03*
X54062Y257049D03*
X49244Y360352D03*
X49730Y412473D03*
X45530D03*
X52150Y414896D03*
X47900Y414660D03*
X44360Y414915D03*
X49640Y430237D03*
X45410Y430444D03*
X51350Y433695D03*
X47420Y433725D03*
X44360Y433729D03*
X49625Y478472D03*
Y480972D03*
X50330Y497940D03*
X53330D03*
X49645Y491804D03*
Y489304D03*
X47380Y494638D03*
X53622Y509276D03*
X53330Y506417D03*
Y503817D03*
X50330D03*
X46140Y541712D03*
X43850Y602797D03*
X50170Y636895D03*
X59524Y25922D03*
X68756Y167695D03*
X56190Y170026D03*
X59640Y161376D03*
X57257Y180712D03*
X55963Y199565D03*
X57749Y204326D03*
X56383Y218543D03*
X63720Y228683D03*
X56936Y223944D03*
X57624Y366105D03*
X66747Y466363D03*
X64050Y465689D03*
X61183Y465314D03*
X65438Y510666D03*
X61033Y510705D03*
X61003Y515110D03*
X65478D03*
X56148Y530809D03*
X67260Y546688D03*
X63300Y621755D03*
X63490Y630693D03*
X79360Y46044D03*
X82065Y73224D03*
X80845Y106859D03*
X81030Y172605D03*
X78850Y157866D03*
X82030Y191733D03*
X75236Y188946D03*
X75359Y201109D03*
X85876Y218939D03*
X78190Y214642D03*
X72150Y225148D03*
X78614Y229920D03*
X79217Y232861D03*
X79544Y267579D03*
X82368Y297135D03*
X72368Y287906D03*
X73917Y385722D03*
X74031Y393857D03*
X85951Y410263D03*
X83455Y489485D03*
Y491985D03*
X85955Y489485D03*
Y491985D03*
X83455Y494485D03*
X85955D03*
X81635Y517104D03*
Y513104D03*
X72216Y540493D03*
X73130Y601599D03*
X73180Y611184D03*
X80630Y689682D03*
X82847Y716068D03*
X82736Y791695D03*
Y788695D03*
X70925D03*
Y791695D03*
X97830Y66508D03*
X98531Y121340D03*
X90878Y177967D03*
X86560Y205852D03*
X96168Y231618D03*
X93200Y300734D03*
X99968Y367705D03*
X95968Y367814D03*
X98410Y421908D03*
X98470Y418834D03*
X101650Y428745D03*
Y425552D03*
Y433296D03*
Y436075D03*
X101590Y446203D03*
X101650Y443038D03*
X86726Y501997D03*
X88563Y491984D03*
Y489484D03*
Y494484D03*
X91458Y511853D03*
X98410Y680541D03*
X100223Y733207D03*
X94547Y788695D03*
Y791695D03*
X115628Y104405D03*
X106517Y210796D03*
X110490Y397362D03*
X116960Y394023D03*
X114207Y417910D03*
Y414910D03*
X105670Y411262D03*
X117980Y451981D03*
X118020Y455079D03*
X114372Y518898D03*
X109640Y611890D03*
X109410Y621425D03*
X109500Y616724D03*
X109260Y644687D03*
Y648989D03*
X117790Y667235D03*
X115748Y716275D03*
X114232Y791695D03*
Y788695D03*
X126460Y250160D03*
X126570Y256194D03*
X129660Y279890D03*
X130310Y269174D03*
X123160Y287060D03*
X129610Y287115D03*
X122729Y398001D03*
X127729D03*
X125229D03*
X128226Y413925D03*
X125726D03*
X123226D03*
X121080Y460060D03*
X124040Y459746D03*
X127060Y460040D03*
X121360Y472028D03*
X118720Y471989D03*
X132960Y550005D03*
X125340Y558090D03*
X129607Y686735D03*
X120357Y738889D03*
X120322Y742187D03*
X123518Y742030D03*
X146558Y74863D03*
X147570Y249033D03*
X147160Y242219D03*
X143150Y281123D03*
X137925Y290987D03*
X136130Y305640D03*
X137091Y301799D03*
X135730Y314543D03*
X134768Y319043D03*
X135224Y323543D03*
X136506Y332193D03*
X144058Y376025D03*
X135507Y421367D03*
X147820Y441929D03*
X145020Y576001D03*
X147753Y627557D03*
X145750Y630254D03*
X147750Y687539D03*
X143823Y682907D03*
X134753Y726161D03*
X137070Y728012D03*
X141791Y788695D03*
Y791695D03*
X161221Y89447D03*
X160040Y108844D03*
X162130Y129344D03*
X160449Y259605D03*
X158583Y285548D03*
X161918Y293869D03*
X162017Y324389D03*
X152058Y376016D03*
X160058Y375818D03*
X150524Y382808D03*
X161577Y436834D03*
X161563Y432521D03*
X158430Y568437D03*
X149860Y726626D03*
X177224Y49101D03*
X174724D03*
X177224Y51601D03*
X174724D03*
X172224Y49101D03*
Y54101D03*
X177224D03*
X174724D03*
X172224Y51601D03*
X177757Y88271D03*
X168308Y88412D03*
X180990Y108770D03*
X177210Y97657D03*
X165690Y98835D03*
X171950Y105105D03*
X167127Y120603D03*
X174213Y120569D03*
X171320Y243601D03*
X166189Y335285D03*
X167383Y341306D03*
X177604Y355155D03*
X177720Y352522D03*
X177029Y347811D03*
X177672Y358103D03*
X176058Y376568D03*
X168058Y376035D03*
X167951Y380551D03*
X170506Y424127D03*
X173151Y427552D03*
X172944Y448387D03*
X170444D03*
X179857Y477790D03*
X169293Y562358D03*
X171180Y652009D03*
X171270Y655650D03*
X179180Y675205D03*
X174761Y663816D03*
X178278Y705976D03*
Y701976D03*
Y697976D03*
Y709976D03*
X171689Y728920D03*
X173287Y791695D03*
Y788695D03*
X184843Y88467D03*
X191930Y88507D03*
X196000Y95568D03*
X195473Y108767D03*
X184170Y95213D03*
X186060Y100103D03*
X196010Y125188D03*
X186730Y121202D03*
X188821Y232784D03*
X189192Y243061D03*
X187404Y343998D03*
X186925Y355812D03*
X186908Y352760D03*
X184058Y376479D03*
X194231Y390267D03*
X194330Y396425D03*
X192676Y402961D03*
X182771Y424013D03*
X185271D03*
X182771Y421513D03*
X185271D03*
X192069Y444852D03*
X185747Y487664D03*
X188654Y573395D03*
X188200Y672526D03*
X196463Y685036D03*
X182163Y684555D03*
X194508Y704476D03*
X187798Y704513D03*
X185440Y712499D03*
X196144Y712602D03*
X187744Y708356D03*
X191930Y712624D03*
X194440Y735623D03*
X189940Y735681D03*
X185440D03*
X182674Y730521D03*
X199016Y88434D03*
X206103Y88207D03*
X202560Y107797D03*
X210203Y108457D03*
X206273Y98364D03*
X207070Y179744D03*
X207154Y175212D03*
X207041Y184502D03*
X207070Y188978D03*
X197243Y344518D03*
X206817Y358874D03*
X207274Y353124D03*
X202823Y376922D03*
X200439Y390168D03*
X203880Y385272D03*
X200488Y396425D03*
X200039Y448750D03*
Y451350D03*
X197809Y469953D03*
X200434Y478345D03*
X208710Y500856D03*
X211379Y501904D03*
X208050Y528883D03*
X209886Y539962D03*
X201509Y539853D03*
X199709Y551653D03*
X208109Y551053D03*
X209238Y674373D03*
X210023Y712842D03*
X201663Y712694D03*
X198940Y712499D03*
X212440Y735829D03*
X198940Y735681D03*
X207940D03*
X203440D03*
X200846Y788695D03*
Y791695D03*
X225990Y21219D03*
X221990D03*
X221600Y66317D03*
X225600D03*
X213190Y88414D03*
X220276Y88440D03*
X214573Y93771D03*
X219095Y108675D03*
X217040Y103121D03*
X226713Y122007D03*
X223561Y385108D03*
X214008Y385165D03*
X221438Y390655D03*
X226276Y460704D03*
X213994Y466054D03*
X214626Y516492D03*
X227329Y508894D03*
X216564Y528902D03*
X223453Y578087D03*
X216590Y570850D03*
X220428Y580271D03*
X221129Y642363D03*
X215768Y671993D03*
X224289Y680081D03*
X224360Y684366D03*
X213365Y692151D03*
X226610Y713482D03*
X216940Y736063D03*
X221440Y735934D03*
X225940Y724061D03*
X220532Y788695D03*
Y791695D03*
X212658D03*
Y788695D03*
X241990Y21219D03*
X229990D03*
X237600Y66317D03*
X241600D03*
X229600D03*
X233600D03*
X236360Y93931D03*
X236812Y88698D03*
X229725Y88719D03*
X243730Y103057D03*
X240355Y108757D03*
X239500Y100925D03*
X231910Y105731D03*
X235190Y96905D03*
X233268Y121742D03*
X233697Y353961D03*
X243940Y390885D03*
X236687Y385234D03*
X232172Y388814D03*
X240599Y440053D03*
X242915Y576539D03*
X239269Y597128D03*
X229809Y583627D03*
X229584Y652668D03*
X237451Y652761D03*
X243596Y671772D03*
X229895Y671672D03*
X240493Y692678D03*
X238348Y712469D03*
X243900Y724662D03*
X239440Y736140D03*
X230440Y736412D03*
X234940Y724325D03*
X240217Y788695D03*
Y791695D03*
X232343D03*
Y788695D03*
X249990Y21219D03*
X245990D03*
X257270Y29334D03*
X258300Y22289D03*
X253810Y63244D03*
X245600Y66317D03*
X249600D03*
X246073Y92197D03*
X256573Y94097D03*
X247870Y105821D03*
X250399Y296848D03*
X253611Y293765D03*
X254819Y332435D03*
X250466Y344381D03*
X245691Y341215D03*
X251334Y352857D03*
X250661Y384780D03*
X244196Y419610D03*
Y417010D03*
Y427610D03*
Y425010D03*
Y433010D03*
Y435610D03*
X253709Y586128D03*
X249462Y648383D03*
X257271Y671772D03*
X253398Y692357D03*
X254940Y712381D03*
X253340Y724726D03*
X248440Y736163D03*
X257440Y736041D03*
X252940Y736318D03*
X252028Y791695D03*
X271421Y7319D03*
X268579Y19365D03*
X265934Y16522D03*
X268372Y40782D03*
X265872D03*
X273873Y63167D03*
X269793D03*
X261750Y75886D03*
X267703Y89397D03*
X265830Y102566D03*
X264210Y96914D03*
X267020Y257079D03*
X265886Y271718D03*
X270430Y665576D03*
X269709Y672575D03*
X270140Y691038D03*
X265300Y702131D03*
X275440Y735626D03*
X261940Y735878D03*
X266440Y736030D03*
X270940Y735642D03*
X271713Y788695D03*
Y791695D03*
X259902D03*
X280699Y13908D03*
X278199D03*
X282180Y10253D03*
X285703Y9813D03*
X280699Y16408D03*
X278199D03*
X287476Y37125D03*
X290823Y63167D03*
X282023D03*
X277853D03*
X277000Y88323D03*
X286263Y88677D03*
X287595Y106109D03*
X279010Y104889D03*
X286710Y95717D03*
X276507Y295816D03*
X276687Y385100D03*
X283820Y396266D03*
X281142Y402379D03*
X276809Y471853D03*
X276347Y459741D03*
X284332Y472834D03*
X282298Y483803D03*
X289171Y661908D03*
X288880Y689467D03*
X278341Y717269D03*
X279940Y724126D03*
X289240Y724687D03*
X283990Y734977D03*
X279587Y791695D03*
X295307Y41260D03*
X295390Y44017D03*
X295610Y50299D03*
X295560Y52907D03*
X294903Y63167D03*
X306693D03*
X303053D03*
X298883D03*
X296093Y88477D03*
X302853Y89057D03*
X294800Y100593D03*
X295490Y97209D03*
X302370Y95215D03*
X293873Y130357D03*
X297668Y300709D03*
X298202Y374572D03*
X301240Y470885D03*
X291327Y466811D03*
X306220Y477125D03*
X296913Y514460D03*
X301457Y513837D03*
X291357Y586128D03*
X305602Y620685D03*
Y618185D03*
X299090Y634421D03*
X305200Y652883D03*
X301696Y701851D03*
Y699351D03*
X291790Y735976D03*
X306540Y724266D03*
X297940Y724377D03*
X302660Y736359D03*
X298160Y736489D03*
X291398Y792234D03*
X299272Y791695D03*
X314640Y63167D03*
X310483D03*
X318543D03*
X322713D03*
X314830Y92851D03*
X312183Y88837D03*
X321463Y88517D03*
X321643Y321928D03*
X309143D03*
X311643D03*
X314143D03*
X316643D03*
X319143D03*
X322765Y327721D03*
X322210Y336696D03*
X319323Y338320D03*
X309510Y344127D03*
X319666Y354376D03*
X309131Y374573D03*
X314860Y367656D03*
X315383Y387863D03*
X315533Y384749D03*
X316963Y467655D03*
X316956Y478833D03*
X313347Y570695D03*
X312641Y611556D03*
X307996Y611536D03*
X312656Y606881D03*
X307994Y606886D03*
X308102Y620685D03*
Y618185D03*
X307574Y633762D03*
X314790Y652049D03*
X317130Y653628D03*
X322440Y700130D03*
X320110Y703093D03*
X317580Y719996D03*
X307940Y736445D03*
X311440Y735831D03*
X315940Y735924D03*
X320440Y736031D03*
X311083Y791871D03*
X318957Y791695D03*
X336316Y31815D03*
X326353Y63167D03*
X336024Y88176D03*
X329643Y89887D03*
X336340Y99265D03*
X327950Y101057D03*
X323000Y94337D03*
X332453Y122297D03*
X331376Y299883D03*
X332700Y333089D03*
X334816Y367787D03*
X337316Y367758D03*
X337330Y372679D03*
X334816Y372609D03*
X325749Y418701D03*
X336218Y424850D03*
X325180Y432577D03*
X323154Y556367D03*
Y558867D03*
Y553867D03*
X337550Y558618D03*
Y556118D03*
Y553618D03*
X325841Y719731D03*
X336990Y735701D03*
X324940Y736067D03*
X329440Y735814D03*
X333940Y735895D03*
X339162Y9304D03*
Y11904D03*
X350411Y21277D03*
X339239Y24232D03*
X339471Y19373D03*
Y16773D03*
X339239Y26832D03*
X350198Y88277D03*
X343111Y88429D03*
X344770Y101718D03*
X351793Y105404D03*
X344073Y124397D03*
X351533Y124697D03*
X351373Y134367D03*
X345297Y284849D03*
X342955Y291523D03*
X354170Y308924D03*
X351500Y301795D03*
X342759Y599193D03*
X339616Y603438D03*
Y605938D03*
X339384Y611544D03*
X339600Y621293D03*
Y618693D03*
X339384Y614144D03*
X353298Y633903D03*
X351728Y653860D03*
X339930Y661219D03*
X340525Y686600D03*
X344780Y713349D03*
X343730Y724581D03*
X350180Y735880D03*
X350580Y724427D03*
X346516Y790294D03*
X358285Y21325D03*
X356550Y74767D03*
X366733Y88477D03*
X359646Y88174D03*
X360827Y108541D03*
X362300Y98674D03*
X367560Y120823D03*
X354580Y298101D03*
X357400Y307608D03*
X362660Y316986D03*
X357110Y329210D03*
X359410Y317080D03*
X359120Y331164D03*
X357040Y332970D03*
X360960Y389080D03*
X368943Y506356D03*
X366426Y527722D03*
Y530222D03*
Y532722D03*
X368238Y522673D03*
X365329Y546121D03*
X368694Y546159D03*
X367858Y657573D03*
X365070Y658065D03*
X362173Y665128D03*
X367399Y684652D03*
X367866Y677326D03*
X361646Y689228D03*
X364844Y698332D03*
X361786Y699128D03*
X361717Y695128D03*
X366510Y723622D03*
X361350Y720720D03*
X361490Y712505D03*
X363162Y739537D03*
X366430Y731459D03*
X357096Y732976D03*
X360246Y730819D03*
X363359Y743537D03*
X366201Y787976D03*
X354390Y790294D03*
X366201Y790976D03*
X379940Y17789D03*
X382990Y17519D03*
X380906Y88134D03*
X373820Y88400D03*
X384450Y108830D03*
X372620Y98355D03*
X384090Y98743D03*
X379160Y102923D03*
X374030Y95000D03*
X377363Y121108D03*
X376150Y430405D03*
X373850Y496585D03*
X379177Y509798D03*
X383924Y514797D03*
X385040Y521754D03*
X384588Y526069D03*
X382632Y530322D03*
Y527822D03*
Y532822D03*
X384485Y552365D03*
X382595Y554166D03*
X385573Y629998D03*
X371407Y641507D03*
X380101Y660239D03*
X375575Y739459D03*
X370430Y749138D03*
X376960Y788580D03*
Y791580D03*
X399002Y17519D03*
X393371Y72919D03*
X399804Y88778D03*
X397442Y90667D03*
X389400Y89232D03*
X399653Y108357D03*
X391536Y108990D03*
X398820Y95823D03*
X391190Y104173D03*
X388860Y98010D03*
X399150Y131773D03*
X391880Y131692D03*
X399858Y249711D03*
X399298Y257231D03*
X391998Y258251D03*
X392668Y272511D03*
X400928Y293151D03*
X396098Y283931D03*
X389107Y492097D03*
X400589Y611672D03*
X400587Y607022D03*
X398195Y620821D03*
X400695Y618321D03*
X398195D03*
X400695Y620821D03*
X392063Y624109D03*
X396940Y658078D03*
X396478Y661529D03*
X399911Y661325D03*
X400267Y684029D03*
X390000Y689724D03*
X389961Y682218D03*
X389350Y711288D03*
X414949Y75291D03*
X403739Y72783D03*
X404528Y88702D03*
X405688Y253581D03*
X405038Y267521D03*
X401728Y277251D03*
X409054Y483084D03*
X412260Y482881D03*
X405234Y611692D03*
X405249Y607017D03*
X405426Y626809D03*
X413930Y639810D03*
X410989Y652957D03*
X415834Y693272D03*
X409581Y711643D03*
X413940Y735665D03*
X421473Y160556D03*
Y157556D03*
X422698Y244301D03*
X422288Y250661D03*
X419038Y242611D03*
X427768Y253569D03*
X422178Y266891D03*
X428208Y262109D03*
X426948Y281051D03*
X422918Y289501D03*
X419071Y509283D03*
X422210Y605343D03*
X419221Y612253D03*
X422221Y619873D03*
X422470Y647852D03*
X425146Y672426D03*
X430140Y665660D03*
X417974Y663446D03*
X422510Y677836D03*
X430873Y684536D03*
X425173Y688588D03*
X423317Y705344D03*
X422940Y723802D03*
X420160Y724309D03*
X430940Y735895D03*
X426430Y735126D03*
X418440Y735930D03*
X421321Y791476D03*
X417384D03*
X446268Y69074D03*
X446088Y90159D03*
Y85159D03*
Y87659D03*
X434158Y122272D03*
X443448Y124552D03*
X441518Y122242D03*
X434158Y125092D03*
X444828Y122132D03*
X433253Y160737D03*
X433363Y157607D03*
X442580Y236459D03*
X447900Y265292D03*
X442148Y279361D03*
X442165Y271284D03*
X441076Y294906D03*
X441361Y300812D03*
X437887Y471073D03*
X437516Y587579D03*
X440135Y615808D03*
X433872Y645119D03*
X446980Y638774D03*
X446799Y657526D03*
X444403Y665963D03*
X446900Y714648D03*
X447240Y724780D03*
X439940Y735507D03*
X443940Y735681D03*
X435440Y735928D03*
X436440Y724710D03*
X441006Y791476D03*
X437069D03*
X450618Y69004D03*
X457583Y66384D03*
X462294Y87759D03*
Y85259D03*
Y90259D03*
X453298Y122254D03*
X450798D03*
X452158Y124582D03*
X458818Y122065D03*
Y125422D03*
X455292Y162797D03*
X455470Y166963D03*
X455913Y178698D03*
X452115Y195057D03*
X450576Y234431D03*
X454150Y249053D03*
X457165Y262368D03*
X449290Y276227D03*
X453780Y292411D03*
X461130Y408318D03*
X461080Y411451D03*
X463690Y451813D03*
X461590Y446700D03*
X461540Y449833D03*
X457702Y475480D03*
X460702D03*
X454702D03*
X463702D03*
X450899Y483452D03*
X460236Y581679D03*
X458600Y599200D03*
X453775Y600614D03*
X453935Y624739D03*
X456342Y649436D03*
X458650Y666543D03*
X463120Y681992D03*
X460530Y681874D03*
X459650Y685993D03*
X457730Y682010D03*
X456960Y685581D03*
X461960Y684394D03*
X453530Y736212D03*
X458050Y725053D03*
X462440Y735687D03*
X460691Y791476D03*
X456754D03*
X464767Y78145D03*
X466647Y91224D03*
X466682Y102410D03*
X474381Y125310D03*
X478088Y125219D03*
X474140Y408318D03*
X469590D03*
X465330D03*
X474080Y411451D03*
X469530D03*
X465270D03*
X480050Y419556D03*
X471540Y437214D03*
X473140Y439971D03*
X469500Y447730D03*
X467920Y451667D03*
X472210Y450267D03*
X465730Y449833D03*
X465790Y446700D03*
X479575Y467597D03*
X479754Y462988D03*
X466702Y475480D03*
X473153Y622451D03*
X478905Y659426D03*
X470190Y648693D03*
X479353Y668666D03*
X466049Y675327D03*
X471450Y736368D03*
X466440Y735987D03*
X471310Y733811D03*
X466440Y724465D03*
X474940Y747192D03*
X476439Y791476D03*
X488438Y100123D03*
X484068Y99980D03*
X490760Y154771D03*
X495300Y201600D03*
X491046Y207506D03*
X486738Y210434D03*
X488816Y242877D03*
X495140Y385762D03*
X486670Y426196D03*
X483685Y473522D03*
X483641Y479628D03*
X489938Y563425D03*
X490658Y579025D03*
X487398Y576665D03*
X490693Y570770D03*
X490538Y567825D03*
X485380Y596505D03*
X491100Y644351D03*
X491930Y654203D03*
X495622Y660178D03*
X491157Y675604D03*
X491189Y679656D03*
X494323Y687669D03*
X496000Y736152D03*
X483180Y736506D03*
X487940Y735681D03*
X491890Y735740D03*
X494850Y733252D03*
X480376Y791476D03*
X508904Y124063D03*
X502132Y146686D03*
X498875Y217172D03*
X499075Y235575D03*
X496123Y233500D03*
X504897Y390481D03*
X505819Y417473D03*
X510577Y417741D03*
X498238Y417825D03*
X502687Y417453D03*
X499551Y429636D03*
X502494Y436725D03*
X509464Y450265D03*
X505442Y458719D03*
X511070Y493380D03*
X511520Y496255D03*
X505740Y495880D03*
X511560Y513792D03*
X504613Y522050D03*
X500138Y543225D03*
X503448Y540235D03*
X505718Y542865D03*
X500038Y555925D03*
Y550725D03*
X510338Y571325D03*
X499868Y585725D03*
X505738Y600425D03*
X496140Y608883D03*
X504268Y608625D03*
X498666Y653012D03*
X502890Y736349D03*
X506105Y724132D03*
X500061Y791476D03*
X496124D03*
X518248Y137692D03*
X518477Y141401D03*
X527349Y152246D03*
X526875Y161838D03*
X511997Y207730D03*
X519183Y224173D03*
X519300Y220500D03*
X516625Y230075D03*
X517617Y422944D03*
X514820Y417617D03*
X526440Y432077D03*
X515780Y434039D03*
X513140Y452621D03*
X519440Y452321D03*
X526340D03*
X513140Y459721D03*
Y466021D03*
X525640Y473021D03*
X519640D03*
X513140D03*
X516353Y480708D03*
X519490Y496645D03*
X525698Y496724D03*
X522250Y513692D03*
X527138Y529525D03*
X523938Y528725D03*
X515110Y528785D03*
X519438Y543025D03*
X513480Y541499D03*
X513838Y556925D03*
X512354Y590825D03*
X519638Y600425D03*
X523538Y600325D03*
X527438D03*
X519830Y634663D03*
X515371Y658880D03*
X515425Y685783D03*
X518500Y723073D03*
X519440Y735681D03*
X512140Y736554D03*
X514901Y724120D03*
X523370Y724131D03*
X519746Y791476D03*
X515809D03*
X542248Y106333D03*
X527898Y147146D03*
X533483Y177449D03*
X533797Y180764D03*
X536676Y234993D03*
X536576Y246993D03*
X529527Y265584D03*
X529910Y419478D03*
X541440Y431787D03*
X536440Y431923D03*
X531440Y432178D03*
X542738Y455823D03*
X530038Y444323D03*
X533040Y453221D03*
X533740Y458021D03*
Y465021D03*
X542738Y463123D03*
X533740Y473021D03*
X540938Y473623D03*
X535729Y476632D03*
X539419Y491107D03*
X532934Y491384D03*
X530638Y539525D03*
X534638Y539825D03*
X541238Y539625D03*
X533038Y590325D03*
X536438Y600425D03*
X542438Y613723D03*
X538400Y613804D03*
X540048Y629641D03*
X535230Y648711D03*
X535485Y715182D03*
X537702Y735662D03*
X541940Y735681D03*
X528440D03*
X531845Y724095D03*
X539431Y791476D03*
X535494D03*
X547248Y106582D03*
X548367Y135415D03*
X548007Y139415D03*
X547543Y143415D03*
X558845Y158697D03*
X558768Y191223D03*
X553909Y207401D03*
X547927Y212190D03*
X558416Y210682D03*
X544700Y216100D03*
X547148Y220220D03*
X555707Y389146D03*
X543381Y448428D03*
X556771Y456156D03*
X556959Y443009D03*
X551140Y445789D03*
X556971Y460656D03*
X547340Y484025D03*
X548000Y509493D03*
X547880Y515743D03*
X544138Y530125D03*
X545413Y547950D03*
X551438Y561225D03*
X551538Y568525D03*
X550938Y587325D03*
X548138Y600425D03*
X544638Y600525D03*
X553619Y601204D03*
X546938Y613828D03*
X552849Y631652D03*
X545377Y647594D03*
X547346Y697581D03*
X544984Y699419D03*
X555148Y735583D03*
X550940Y735681D03*
X546440D03*
X555179Y791476D03*
X561909Y207393D03*
X571576Y246693D03*
X564676D03*
X571476Y260093D03*
X564676D03*
Y253693D03*
X567320Y415088D03*
X561610Y503885D03*
X560960Y510151D03*
X571830Y509411D03*
X567791Y528325D03*
X568068Y525306D03*
X561065Y543998D03*
X560838Y540325D03*
X574738Y579525D03*
X574537Y591325D03*
X574738Y587425D03*
X574645Y583525D03*
X565168Y684614D03*
X568215Y702343D03*
X568288Y715547D03*
X568908Y735883D03*
X573440Y735681D03*
X564438Y735853D03*
X560350Y735807D03*
X573440Y724053D03*
X568940Y724090D03*
X562395Y724557D03*
X559116Y791476D03*
X578938Y103123D03*
X583829Y117732D03*
X583661Y121836D03*
X584438Y160933D03*
X579707Y220662D03*
X578076Y246693D03*
Y253393D03*
Y260093D03*
X575874Y282395D03*
Y289895D03*
Y285995D03*
X583853Y313783D03*
X585584Y308881D03*
X579168Y313641D03*
X583737Y321204D03*
X575550Y463784D03*
X575650Y469996D03*
X579600Y508878D03*
X585013Y547959D03*
X575438Y545425D03*
X575238Y552025D03*
X575038Y567725D03*
X575538Y571725D03*
X574876Y575625D03*
X586369Y585801D03*
X579500Y625963D03*
X587440Y656958D03*
X576700Y655594D03*
X584903Y663828D03*
X586060Y682582D03*
X587040Y688218D03*
X586995Y694080D03*
X583440Y735856D03*
X587940Y735681D03*
X587963Y724108D03*
X577940Y724127D03*
X578802Y791476D03*
X574864D03*
X594920Y123370D03*
X592491Y175906D03*
X595707Y220995D03*
X597074Y239995D03*
X600874Y239795D03*
X604774Y249795D03*
X596774D03*
X600874D03*
X604674Y239995D03*
X592874Y250995D03*
X605674Y236295D03*
X596574Y268695D03*
X600674Y268795D03*
X604574D03*
X604926Y278476D03*
X604774Y271893D03*
X592201Y308988D03*
X591977Y319360D03*
X605746Y387837D03*
X605573Y393920D03*
X605798Y501238D03*
X596751Y532108D03*
X605521Y601097D03*
X594733Y653385D03*
X601588Y664798D03*
X592440Y723768D03*
X596860Y723422D03*
X601440Y735681D03*
X605938Y735665D03*
X596940Y735681D03*
X593004Y735662D03*
X598487Y791476D03*
X594550D03*
X618623Y108918D03*
X608274Y249795D03*
X608774Y239995D03*
X608274Y268795D03*
X613640Y336986D03*
X608869Y396959D03*
X608821Y403445D03*
X621760Y526967D03*
X609300Y531638D03*
X613541Y546764D03*
X614579Y645072D03*
X610651Y675156D03*
X614909Y671938D03*
X617235Y689036D03*
X621410Y696941D03*
X607020Y704644D03*
X611244Y709830D03*
X621254Y713788D03*
X617093Y709167D03*
X619590Y735383D03*
X614732Y735517D03*
X608791Y735775D03*
X618172Y791476D03*
X614235D03*
X610298D03*
X624358Y176090D03*
X632483Y192781D03*
X624950Y189801D03*
X632485Y202077D03*
X633633Y403717D03*
X633663Y411009D03*
X634945Y461888D03*
X635545Y465888D03*
X622199Y506535D03*
X634190Y538267D03*
X634251Y683493D03*
X623940Y723503D03*
X623960Y735141D03*
X628380Y735476D03*
X629983Y791476D03*
X633920D03*
X638970Y132241D03*
X646013Y358110D03*
X647440Y386383D03*
X647340Y393283D03*
X647440Y408383D03*
X647340Y400083D03*
X651138Y417385D03*
X641480Y430289D03*
X650079D03*
X646381Y478679D03*
X646105Y492010D03*
X646906Y505210D03*
X648077Y713569D03*
X653500Y732583D03*
X639928Y738905D03*
X658769Y143630D03*
X658767Y151013D03*
X658959Y165625D03*
X658972Y158337D03*
X667300Y188112D03*
X660700Y203282D03*
X669250Y203317D03*
X665320Y203247D03*
X664560Y195018D03*
Y191443D03*
X660770Y214951D03*
X665390Y214916D03*
X661160Y235485D03*
X658582Y222614D03*
X658601Y229770D03*
X661190Y246085D03*
X666270Y359134D03*
X660138Y365885D03*
X654340Y386283D03*
X661140D03*
X654840Y408483D03*
X661940Y408383D03*
X666312Y417742D03*
X656021Y427864D03*
X665766Y427868D03*
X664528Y463432D03*
X667428D03*
X666928Y468132D03*
X659740Y536019D03*
X668000Y676595D03*
X656254Y683277D03*
X663040Y688057D03*
X654514Y720674D03*
X656660Y736218D03*
X661479Y791476D03*
X665416D03*
X679927Y53881D03*
X670980Y77061D03*
X671810Y106472D03*
X670280Y188112D03*
X669320Y214986D03*
X672752Y366160D03*
X679552Y372873D03*
X669540Y386283D03*
X678099Y389915D03*
X674235Y379364D03*
X669440Y395183D03*
Y408483D03*
X669540Y402783D03*
X678338Y405185D03*
X683128Y451332D03*
X680228Y451432D03*
X670428Y463532D03*
X669728Y468032D03*
X672628D03*
X678315Y540752D03*
X669390Y695406D03*
X672630Y720752D03*
X688160Y64459D03*
X689500Y120441D03*
X691148Y140140D03*
X691280Y149571D03*
X691314Y145071D03*
X687571Y172292D03*
X687584Y251770D03*
X689864Y392130D03*
X687121Y407004D03*
X689864Y398141D03*
X686731Y413349D03*
X691161Y518684D03*
X691532Y559789D03*
Y563789D03*
Y567789D03*
Y571789D03*
Y575789D03*
Y579789D03*
Y583789D03*
Y587789D03*
X695600Y590788D03*
X689100Y680291D03*
X688510Y735294D03*
X707176Y50574D03*
X706380Y75482D03*
X708130Y106389D03*
X701687Y212132D03*
X700947Y216868D03*
X700994Y221368D03*
X707942Y448676D03*
X714639Y454872D03*
X712239Y452293D03*
X712281Y525785D03*
X710585Y539103D03*
X701023Y553658D03*
X710873Y563230D03*
X715282Y620282D03*
X711612Y620383D03*
X708450Y695489D03*
X705870Y721832D03*
X706575Y740425D03*
X704786Y791274D03*
X708723Y791092D03*
X709040Y787507D03*
X726160Y109316D03*
X726190Y105325D03*
X726160Y112508D03*
X731566Y442136D03*
X729942Y515757D03*
X720052Y620480D03*
X729500Y737400D03*
X721790Y791408D03*
X722590Y787885D03*
X738620Y109351D03*
X738650Y105360D03*
X738620Y112543D03*
X741401Y454832D03*
X742779Y487639D03*
X734460Y788654D03*
Y791654D03*
X762590Y106529D03*
X762630Y103302D03*
X757500Y474000D03*
X748300Y496800D03*
X766840Y561290D03*
X766920Y564080D03*
X766950Y558318D03*
X766820Y569897D03*
X766900Y567233D03*
Y572869D03*
X771110Y578643D03*
X770850Y575760D03*
X770710Y584054D03*
X770850Y587025D03*
G54D35*
X227326Y505741D03*
X230476D03*
X236776Y508891D03*
X252524Y527789D03*
Y524639D03*
X255673Y534088D03*
X252524D03*
X249374D03*
X255673Y524639D03*
Y527789D03*
X249374D03*
Y524639D03*
X255673Y537237D03*
X249374D03*
X252524D03*
X255673Y540387D03*
X249374D03*
X252524D03*
X255673Y565580D03*
Y552984D03*
Y556133D03*
Y559282D03*
Y562431D03*
X249344Y552984D03*
Y556134D03*
X265122Y502591D03*
X268272Y505741D03*
Y508891D03*
X261972Y521489D03*
X268272Y534088D03*
X265122D03*
X261972D03*
X268272Y524639D03*
Y527789D03*
X265122D03*
Y524639D03*
X261972D03*
Y527789D03*
X268272Y521489D03*
X265122D03*
X268272Y540387D03*
X265122D03*
X261972D03*
X265122Y537237D03*
X268272D03*
X261972D03*
X274571Y552985D03*
X265122D03*
X268272Y559291D03*
X271422Y562434D03*
X271421Y556135D03*
X271422Y559291D03*
X261973Y552985D03*
X261972Y562431D03*
X271422Y565583D03*
X290323Y534092D03*
X280874D03*
X287174D03*
X284024D03*
X280874Y537241D03*
Y543541D03*
X284024D03*
X287174Y540391D03*
Y543541D03*
X290323Y540391D03*
Y543541D03*
X287174Y559289D03*
X290323Y565589D03*
X284024Y565588D03*
X287174D03*
X290323Y559289D03*
Y562439D03*
Y556140D03*
X287174Y562438D03*
X280874D03*
X284024D03*
Y559289D03*
X277725Y552989D03*
X280874Y559289D03*
X277725Y556135D03*
Y559289D03*
X287174Y556139D03*
X280874Y552989D03*
X284024Y556139D03*
X287174Y552989D03*
X284024D03*
X293473Y534092D03*
Y540391D03*
Y565589D03*
Y562439D03*
Y559290D03*
G54D50*
X605796Y174845D03*
Y189845D03*
G54D16*
X10859Y109561D03*
G54D42*
X507489Y360278D03*
G54D45*
X546181Y81889D03*
G54D43*
X514780Y28803D03*
X554780D03*
X577371D03*
X617371D03*
X639963D03*
X679963D03*
G54D49*
X605796Y165160D03*
X609733Y215672D03*
G54D24*
X45282Y321764D03*
Y338300D03*
%LPC*%
G75*
G36*
G01X-36897Y131113D02*
G02X-34847I1025J-400D01*
G01X-33897D01*
G02Y130313I1025J-400D01*
G01X-34847D01*
G02X-36897I-1025J400D01*
G01X-37847D01*
G02Y131113I-1025J400D01*
G01X-36897D01*
G37*
G36*
G01Y238433D02*
G02X-34847I1025J-400D01*
G01X-33897D01*
G02Y237633I1025J-400D01*
G01X-34847D01*
G02X-36897I-1025J400D01*
G01X-37847D01*
G02Y238433I-1025J400D01*
G01X-36897D01*
G37*
G36*
G01X-34847D02*
G03X-36897I-1025J-400D01*
G01X-37847D01*
G03Y237633I-1025J-400D01*
G01X-36897D01*
G03X-34847I1025J400D01*
G01X-33897D01*
G03Y238433I1025J400D01*
G01X-34847D01*
G37*
G36*
G01Y748593D02*
G02X-36897I-1025J400D01*
G01X-37847D01*
G02Y749393I-1025J400D01*
G01X-36897D01*
G02X-34847I1025J-400D01*
G01X-33897D01*
G02Y748593I1025J-400D01*
G01X-34847D01*
G37*
G54D55*
G01X38493Y-241864D02*
Y-246864D01*
G01X37036Y-241864D02*
X39950D01*
G01X44860Y-246864D02*
X42326D01*
Y-241864D01*
X44860D01*
G01X43846Y-244281D02*
X42326D01*
G01X47426Y-241864D02*
Y-246864D01*
X49960D01*
G01X53793Y-247031D02*
X53666Y-246947D01*
Y-246781D01*
X53793Y-246697D01*
X53920Y-246781D01*
Y-246947D01*
X53793Y-247031D01*
G01Y-244781D02*
X53666Y-244697D01*
Y-244531D01*
X53793Y-244447D01*
X53920Y-244531D01*
Y-244697D01*
X53793Y-244781D01*
G01X58576Y-248531D02*
X57943Y-247697D01*
X57626Y-246864D01*
Y-243531D01*
X57943Y-242697D01*
X58576Y-241864D01*
G01X63993D02*
X63486Y-242031D01*
X63106Y-242447D01*
X62853Y-242947D01*
X62663Y-243614D01*
X62600Y-244364D01*
X62663Y-245114D01*
X62853Y-245781D01*
X63106Y-246281D01*
X63486Y-246697D01*
X63993Y-246864D01*
X64500Y-246697D01*
X64880Y-246281D01*
X65133Y-245781D01*
X65323Y-245114D01*
X65386Y-244364D01*
X65323Y-243614D01*
X65133Y-242947D01*
X64880Y-242447D01*
X64500Y-242031D01*
X63993Y-241864D01*
G01X67700Y-245864D02*
X68080Y-246447D01*
X68586Y-246781D01*
X69156Y-246864D01*
X69663Y-246781D01*
X70170Y-246364D01*
X70486Y-245864D01*
X70550Y-245364D01*
X70423Y-244781D01*
X69980Y-244364D01*
X69536Y-244197D01*
X68966D01*
G01X69536D02*
X69916Y-243947D01*
X70233Y-243531D01*
X70360Y-243031D01*
X70233Y-242531D01*
X69916Y-242114D01*
X69346Y-241864D01*
X68776Y-241947D01*
X68206Y-242281D01*
G01X74510Y-248531D02*
X75143Y-247697D01*
X75460Y-246864D01*
Y-243531D01*
X75143Y-242697D01*
X74510Y-241864D01*
G01X77900Y-245864D02*
X78280Y-246447D01*
X78786Y-246781D01*
X79356Y-246864D01*
X79863Y-246781D01*
X80370Y-246364D01*
X80686Y-245864D01*
X80750Y-245364D01*
X80623Y-244781D01*
X80180Y-244364D01*
X79736Y-244197D01*
X79166D01*
G01X79736D02*
X80116Y-243947D01*
X80433Y-243531D01*
X80560Y-243031D01*
X80433Y-242531D01*
X80116Y-242114D01*
X79546Y-241864D01*
X78976Y-241947D01*
X78406Y-242281D01*
G01X83190Y-242697D02*
X83570Y-242197D01*
X84013Y-241947D01*
X84520Y-241864D01*
X85153Y-242031D01*
X85596Y-242447D01*
X85723Y-242947D01*
X85660Y-243447D01*
X85406Y-243864D01*
X84140Y-244697D01*
X83570Y-245281D01*
X83190Y-246114D01*
X83063Y-246864D01*
X85723D01*
G01X89366D02*
X89493Y-245781D01*
X89683Y-244864D01*
X89936Y-244031D01*
X90253Y-243114D01*
X90760Y-241864D01*
X88226D01*
G01X93770Y-245197D02*
X95416D01*
G01X98490Y-242697D02*
X98870Y-242197D01*
X99313Y-241947D01*
X99820Y-241864D01*
X100453Y-242031D01*
X100896Y-242447D01*
X101023Y-242947D01*
X100960Y-243447D01*
X100706Y-243864D01*
X99440Y-244697D01*
X98870Y-245281D01*
X98490Y-246114D01*
X98363Y-246864D01*
X101023D01*
G01X103400Y-245864D02*
X103780Y-246447D01*
X104286Y-246781D01*
X104856Y-246864D01*
X105363Y-246781D01*
X105870Y-246364D01*
X106186Y-245864D01*
X106250Y-245364D01*
X106123Y-244781D01*
X105680Y-244364D01*
X105236Y-244197D01*
X104666D01*
G01X105236D02*
X105616Y-243947D01*
X105933Y-243531D01*
X106060Y-243031D01*
X105933Y-242531D01*
X105616Y-242114D01*
X105046Y-241864D01*
X104476Y-241947D01*
X103906Y-242281D01*
G01X110653Y-246864D02*
Y-241864D01*
X108310Y-245447D01*
X111476D01*
G01X113600Y-246114D02*
X113980Y-246531D01*
X114423Y-246781D01*
X114993Y-246864D01*
X115563Y-246697D01*
X116006Y-246364D01*
X116323Y-245781D01*
X116386Y-245114D01*
X116260Y-244447D01*
X115943Y-244031D01*
X115500Y-243697D01*
X115056Y-243614D01*
X114613Y-243697D01*
X114043Y-244031D01*
X114233Y-241864D01*
X115943D01*
G01X123990Y-246864D02*
Y-241864D01*
X126396D01*
G01X125510Y-244281D02*
X123990D01*
G01X128710Y-246864D02*
X130293Y-241864D01*
X131876Y-246864D01*
G01X131306Y-245114D02*
X129280D01*
G01X134063Y-246864D02*
X136723Y-241864D01*
G01X134063D02*
X136723Y-246864D01*
G01X140493Y-247031D02*
X140366Y-246947D01*
Y-246781D01*
X140493Y-246697D01*
X140620Y-246781D01*
Y-246947D01*
X140493Y-247031D01*
G01Y-244781D02*
X140366Y-244697D01*
Y-244531D01*
X140493Y-244447D01*
X140620Y-244531D01*
Y-244697D01*
X140493Y-244781D01*
G01X145276Y-248531D02*
X144643Y-247697D01*
X144326Y-246864D01*
Y-243531D01*
X144643Y-242697D01*
X145276Y-241864D01*
G01X150693D02*
X150186Y-242031D01*
X149806Y-242447D01*
X149553Y-242947D01*
X149363Y-243614D01*
X149300Y-244364D01*
X149363Y-245114D01*
X149553Y-245781D01*
X149806Y-246281D01*
X150186Y-246697D01*
X150693Y-246864D01*
X151200Y-246697D01*
X151580Y-246281D01*
X151833Y-245781D01*
X152023Y-245114D01*
X152086Y-244364D01*
X152023Y-243614D01*
X151833Y-242947D01*
X151580Y-242447D01*
X151200Y-242031D01*
X150693Y-241864D01*
G01X154400Y-245864D02*
X154780Y-246447D01*
X155286Y-246781D01*
X155856Y-246864D01*
X156363Y-246781D01*
X156870Y-246364D01*
X157186Y-245864D01*
X157250Y-245364D01*
X157123Y-244781D01*
X156680Y-244364D01*
X156236Y-244197D01*
X155666D01*
G01X156236D02*
X156616Y-243947D01*
X156933Y-243531D01*
X157060Y-243031D01*
X156933Y-242531D01*
X156616Y-242114D01*
X156046Y-241864D01*
X155476Y-241947D01*
X154906Y-242281D01*
G01X161210Y-248531D02*
X161843Y-247697D01*
X162160Y-246864D01*
Y-243531D01*
X161843Y-242697D01*
X161210Y-241864D01*
G01X164600Y-245864D02*
X164980Y-246447D01*
X165486Y-246781D01*
X166056Y-246864D01*
X166563Y-246781D01*
X167070Y-246364D01*
X167386Y-245864D01*
X167450Y-245364D01*
X167323Y-244781D01*
X166880Y-244364D01*
X166436Y-244197D01*
X165866D01*
G01X166436D02*
X166816Y-243947D01*
X167133Y-243531D01*
X167260Y-243031D01*
X167133Y-242531D01*
X166816Y-242114D01*
X166246Y-241864D01*
X165676Y-241947D01*
X165106Y-242281D01*
G01X170016Y-246281D02*
X170460Y-246697D01*
X170966Y-246864D01*
X171473Y-246697D01*
X171916Y-246197D01*
X172233Y-245447D01*
X172360Y-244697D01*
Y-243781D01*
X172233Y-243031D01*
X171916Y-242364D01*
X171536Y-242031D01*
X171093Y-241864D01*
X170586Y-242031D01*
X170206Y-242364D01*
X169953Y-242864D01*
X169826Y-243531D01*
X169953Y-244114D01*
X170270Y-244697D01*
X170650Y-245031D01*
X171093Y-245114D01*
X171600Y-244947D01*
X171980Y-244531D01*
X172360Y-243781D01*
G01X176066Y-246864D02*
X176193Y-245781D01*
X176383Y-244864D01*
X176636Y-244031D01*
X176953Y-243114D01*
X177460Y-241864D01*
X174926D01*
G01X180470Y-245197D02*
X182116D01*
G01X185000Y-245864D02*
X185380Y-246447D01*
X185886Y-246781D01*
X186456Y-246864D01*
X186963Y-246781D01*
X187470Y-246364D01*
X187786Y-245864D01*
X187850Y-245364D01*
X187723Y-244781D01*
X187280Y-244364D01*
X186836Y-244197D01*
X186266D01*
G01X186836D02*
X187216Y-243947D01*
X187533Y-243531D01*
X187660Y-243031D01*
X187533Y-242531D01*
X187216Y-242114D01*
X186646Y-241864D01*
X186076Y-241947D01*
X185506Y-242281D01*
G01X190290Y-244781D02*
X190733Y-244197D01*
X191113Y-243864D01*
X191620Y-243697D01*
X192063Y-243864D01*
X192380Y-244197D01*
X192633Y-244697D01*
X192696Y-245281D01*
X192633Y-245781D01*
X192380Y-246281D01*
X192000Y-246697D01*
X191556Y-246864D01*
X191050Y-246697D01*
X190606Y-246197D01*
X190353Y-245447D01*
X190290Y-244614D01*
X190416Y-243531D01*
X190606Y-242947D01*
X190923Y-242364D01*
X191366Y-241947D01*
X191810Y-241864D01*
X192253Y-242031D01*
X192570Y-242447D01*
G01X196593Y-246864D02*
Y-241864D01*
X195833Y-242864D01*
G01Y-246864D02*
X197353D01*
G01X202453D02*
Y-241864D01*
X200110Y-245447D01*
X203276D01*
G01X26493Y-176864D02*
Y-251864D01*
X526493D01*
Y-176864D01*
X26493D01*
G01X221493D02*
Y-251864D01*
G01Y-226864D02*
X324493D01*
Y-201864D01*
G01X221493D02*
X324493D01*
G01X332000Y-236864D02*
Y-231864D01*
X333266D01*
X333773Y-232114D01*
X334153Y-232447D01*
X334470Y-232947D01*
X334723Y-233531D01*
X334786Y-234364D01*
X334723Y-235197D01*
X334470Y-235781D01*
X334153Y-236281D01*
X333773Y-236614D01*
X333266Y-236864D01*
X332000D01*
G01X336910D02*
X338493Y-231864D01*
X340076Y-236864D01*
G01X339506Y-235114D02*
X337480D01*
G01X343593Y-231864D02*
Y-236864D01*
G01X342136Y-231864D02*
X345050D01*
G01X349960Y-236864D02*
X347426D01*
Y-231864D01*
X349960D01*
G01X348946Y-234281D02*
X347426D01*
G01X353793Y-237031D02*
X353666Y-236947D01*
Y-236781D01*
X353793Y-236697D01*
X353920Y-236781D01*
Y-236947D01*
X353793Y-237031D01*
G01Y-234781D02*
X353666Y-234697D01*
Y-234531D01*
X353793Y-234447D01*
X353920Y-234531D01*
Y-234697D01*
X353793Y-234781D01*
G01X326493Y-176864D02*
Y-251864D01*
G01X324493Y-176864D02*
Y-251864D01*
G01X326493Y-226864D02*
X526493D01*
G01X332126Y-211864D02*
Y-206864D01*
X333646D01*
X334153Y-207114D01*
X334533Y-207697D01*
X334660Y-208364D01*
X334533Y-209031D01*
X334216Y-209531D01*
X333646Y-209781D01*
X332126D01*
G01X337353Y-212031D02*
X339633Y-206864D01*
G01X342136Y-211864D02*
Y-206864D01*
X345050Y-211864D01*
Y-206864D01*
G01X348693Y-212031D02*
X348566Y-211947D01*
Y-211781D01*
X348693Y-211697D01*
X348820Y-211781D01*
Y-211947D01*
X348693Y-212031D01*
G01Y-209781D02*
X348566Y-209697D01*
Y-209531D01*
X348693Y-209447D01*
X348820Y-209531D01*
Y-209697D01*
X348693Y-209781D01*
G01X326493Y-201864D02*
X526493D01*
G01X332126Y-186864D02*
Y-181864D01*
X333646D01*
X334153Y-182114D01*
X334533Y-182697D01*
X334660Y-183364D01*
X334533Y-184031D01*
X334216Y-184531D01*
X333646Y-184781D01*
X332126D01*
G01X337226Y-186864D02*
Y-181864D01*
X338810D01*
X339316Y-182114D01*
X339633Y-182447D01*
X339760Y-183114D01*
X339633Y-183781D01*
X339253Y-184197D01*
X338810Y-184447D01*
X337226D01*
G01X338810D02*
X339760Y-186864D01*
G01X343593D02*
X343086Y-186781D01*
X342643Y-186447D01*
X342263Y-185947D01*
X342010Y-185364D01*
X341883Y-184697D01*
Y-184031D01*
X342010Y-183364D01*
X342263Y-182781D01*
X342643Y-182281D01*
X343086Y-181947D01*
X343593Y-181864D01*
X344100Y-181947D01*
X344543Y-182281D01*
X344923Y-182781D01*
X345176Y-183364D01*
X345303Y-184031D01*
Y-184697D01*
X345176Y-185364D01*
X344923Y-185947D01*
X344543Y-186447D01*
X344100Y-186781D01*
X343593Y-186864D01*
G01X347426Y-185864D02*
X347743Y-186364D01*
X348123Y-186697D01*
X348566Y-186864D01*
X349073Y-186697D01*
X349453Y-186364D01*
X349833Y-185864D01*
X349960Y-185197D01*
Y-181864D01*
G01X355060Y-186864D02*
X352526D01*
Y-181864D01*
X355060D01*
G01X354046Y-184281D02*
X352526D01*
G01X360286Y-182281D02*
X359906Y-182031D01*
X359463Y-181864D01*
X358956D01*
X358386Y-182114D01*
X357943Y-182531D01*
X357626Y-183031D01*
X357373Y-183864D01*
X357310Y-184614D01*
X357436Y-185364D01*
X357626Y-185864D01*
X358006Y-186364D01*
X358450Y-186697D01*
X358893Y-186864D01*
X359336D01*
X359780Y-186697D01*
X360160Y-186447D01*
X360476Y-186114D01*
G01X363993Y-181864D02*
Y-186864D01*
G01X362536Y-181864D02*
X365450D01*
G01X369093Y-187031D02*
X368966Y-186947D01*
Y-186781D01*
X369093Y-186697D01*
X369220Y-186781D01*
Y-186947D01*
X369093Y-187031D01*
G01Y-184781D02*
X368966Y-184697D01*
Y-184531D01*
X369093Y-184447D01*
X369220Y-184531D01*
Y-184697D01*
X369093Y-184781D01*
G01X447126Y-236864D02*
Y-231864D01*
X448710D01*
X449216Y-232114D01*
X449533Y-232447D01*
X449660Y-233114D01*
X449533Y-233781D01*
X449153Y-234197D01*
X448710Y-234447D01*
X447126D01*
G01X448710D02*
X449660Y-236864D01*
G01X454760D02*
X452226D01*
Y-231864D01*
X454760D01*
G01X453746Y-234281D02*
X452226D01*
G01X457010Y-231864D02*
X458593Y-236864D01*
X460176Y-231864D01*
G01X463693Y-237031D02*
X463566Y-236947D01*
Y-236781D01*
X463693Y-236697D01*
X463820Y-236781D01*
Y-236947D01*
X463693Y-237031D01*
G01Y-234781D02*
X463566Y-234697D01*
Y-234531D01*
X463693Y-234447D01*
X463820Y-234531D01*
Y-234697D01*
X463693Y-234781D01*
G01X441493Y-226864D02*
Y-251864D01*
G01X490493Y-226864D02*
Y-251864D01*
G01X-1043962Y-705877D02*
Y2342823D01*
X2300638D01*
Y-705877D01*
X-1043962D01*
G01X37198Y-238524D02*
X37825Y-239049D01*
X38530Y-239364D01*
X39156D01*
X39783Y-239049D01*
X40253Y-238524D01*
X40488Y-237789D01*
X40331Y-237054D01*
X39940Y-236424D01*
X39235Y-236004D01*
X38295Y-235794D01*
X37746Y-235374D01*
X37511Y-234639D01*
X37668Y-233904D01*
X38060Y-233379D01*
X38608Y-233064D01*
X39156D01*
X39705Y-233274D01*
X40175Y-233799D01*
G01X43498Y-239364D02*
Y-233064D01*
G01X46788D02*
Y-239364D01*
G01Y-236214D02*
X43498D01*
G01X50503Y-233064D02*
X52383D01*
G01X51443D02*
Y-239364D01*
G01X50503D02*
X52383D01*
G01X59310D02*
X56176D01*
Y-233064D01*
X59310D01*
G01X58056Y-236109D02*
X56176D01*
G01X62241Y-239364D02*
Y-233064D01*
X65845Y-239364D01*
Y-233064D01*
G01X70186Y-240519D02*
X70500Y-239154D01*
G01X76643Y-233064D02*
Y-239364D01*
G01X74841Y-233064D02*
X78445D01*
G01X80985Y-239364D02*
X82943Y-233064D01*
X84901Y-239364D01*
G01X84196Y-237159D02*
X81690D01*
G01X88303Y-233064D02*
X90183D01*
G01X89243D02*
Y-239364D01*
G01X88303D02*
X90183D01*
G01X93193Y-233064D02*
X94290Y-239364D01*
X95543Y-233064D01*
X96796Y-239364D01*
X97893Y-233064D01*
G01X99885Y-239364D02*
X101843Y-233064D01*
X103801Y-239364D01*
G01X103096Y-237159D02*
X100590D01*
G01X106341Y-239364D02*
Y-233064D01*
X109945Y-239364D01*
Y-233064D01*
G01X119176Y-239364D02*
Y-233064D01*
X121135D01*
X121761Y-233379D01*
X122153Y-233799D01*
X122310Y-234639D01*
X122153Y-235479D01*
X121683Y-236004D01*
X121135Y-236319D01*
X119176D01*
G01X121135D02*
X122310Y-239364D01*
G01X127043Y-239574D02*
X126886Y-239469D01*
Y-239259D01*
X127043Y-239154D01*
X127200Y-239259D01*
Y-239469D01*
X127043Y-239574D01*
G01X133343Y-239364D02*
X132716Y-239259D01*
X132168Y-238839D01*
X131698Y-238209D01*
X131385Y-237474D01*
X131228Y-236634D01*
Y-235794D01*
X131385Y-234954D01*
X131698Y-234219D01*
X132168Y-233589D01*
X132716Y-233169D01*
X133343Y-233064D01*
X133970Y-233169D01*
X134518Y-233589D01*
X134988Y-234219D01*
X135301Y-234954D01*
X135458Y-235794D01*
Y-236634D01*
X135301Y-237474D01*
X134988Y-238209D01*
X134518Y-238839D01*
X133970Y-239259D01*
X133343Y-239364D01*
G01X139643Y-239574D02*
X139486Y-239469D01*
Y-239259D01*
X139643Y-239154D01*
X139800Y-239259D01*
Y-239469D01*
X139643Y-239574D01*
G01X147666Y-233589D02*
X147196Y-233274D01*
X146648Y-233064D01*
X146021D01*
X145316Y-233379D01*
X144768Y-233904D01*
X144376Y-234534D01*
X144063Y-235584D01*
X143985Y-236529D01*
X144141Y-237474D01*
X144376Y-238104D01*
X144846Y-238734D01*
X145395Y-239154D01*
X145943Y-239364D01*
X146491D01*
X147040Y-239154D01*
X147510Y-238839D01*
X147901Y-238419D01*
G01X152243Y-239574D02*
X152086Y-239469D01*
Y-239259D01*
X152243Y-239154D01*
X152400Y-239259D01*
Y-239469D01*
X152243Y-239574D01*
G01X37120Y-229364D02*
Y-223064D01*
G01X40096D02*
X37120Y-226949D01*
G01X40566Y-229364D02*
X38451Y-225164D01*
G01X43420Y-223064D02*
Y-227579D01*
X43733Y-228524D01*
X44360Y-229154D01*
X45143Y-229364D01*
X45926Y-229154D01*
X46553Y-228524D01*
X46866Y-227579D01*
Y-223064D01*
G01X53010Y-229364D02*
X49876D01*
Y-223064D01*
X53010D01*
G01X51756Y-226109D02*
X49876D01*
G01X56803Y-223064D02*
X58683D01*
G01X57743D02*
Y-229364D01*
G01X56803D02*
X58683D01*
G01X68698Y-228524D02*
X69325Y-229049D01*
X70030Y-229364D01*
X70656D01*
X71283Y-229049D01*
X71753Y-228524D01*
X71988Y-227789D01*
X71831Y-227054D01*
X71440Y-226424D01*
X70735Y-226004D01*
X69795Y-225794D01*
X69246Y-225374D01*
X69011Y-224639D01*
X69168Y-223904D01*
X69560Y-223379D01*
X70108Y-223064D01*
X70656D01*
X71205Y-223274D01*
X71675Y-223799D01*
G01X74998Y-229364D02*
Y-223064D01*
G01X78288D02*
Y-229364D01*
G01Y-226214D02*
X74998D01*
G01X80985Y-229364D02*
X82943Y-223064D01*
X84901Y-229364D01*
G01X84196Y-227159D02*
X81690D01*
G01X87441Y-229364D02*
Y-223064D01*
X91045Y-229364D01*
Y-223064D01*
G01X100198Y-229364D02*
Y-223064D01*
G01X103488D02*
Y-229364D01*
G01Y-226214D02*
X100198D01*
G01X106498Y-228524D02*
X107125Y-229049D01*
X107830Y-229364D01*
X108456D01*
X109083Y-229049D01*
X109553Y-228524D01*
X109788Y-227789D01*
X109631Y-227054D01*
X109240Y-226424D01*
X108535Y-226004D01*
X107595Y-225794D01*
X107046Y-225374D01*
X106811Y-224639D01*
X106968Y-223904D01*
X107360Y-223379D01*
X107908Y-223064D01*
X108456D01*
X109005Y-223274D01*
X109475Y-223799D01*
G01X113503Y-223064D02*
X115383D01*
G01X114443D02*
Y-229364D01*
G01X113503D02*
X115383D01*
G01X118785D02*
X120743Y-223064D01*
X122701Y-229364D01*
G01X121996Y-227159D02*
X119490D01*
G01X125241Y-229364D02*
Y-223064D01*
X128845Y-229364D01*
Y-223064D01*
G01X133813Y-226214D02*
X135380D01*
Y-228104D01*
X134910Y-228734D01*
X134361Y-229154D01*
X133578Y-229364D01*
X132795Y-229154D01*
X132246Y-228734D01*
X131776Y-228104D01*
X131463Y-227369D01*
X131306Y-226529D01*
Y-225794D01*
X131463Y-225164D01*
X131776Y-224429D01*
X132246Y-223799D01*
X132716Y-223379D01*
X133343Y-223064D01*
X133891D01*
X134518Y-223274D01*
X134988Y-223694D01*
G01X139486Y-230519D02*
X139800Y-229154D01*
G01X145943Y-223064D02*
Y-229364D01*
G01X144141Y-223064D02*
X147745D01*
G01X150285Y-229364D02*
X152243Y-223064D01*
X154201Y-229364D01*
G01X153496Y-227159D02*
X150990D01*
G01X158543Y-229364D02*
X157916Y-229259D01*
X157368Y-228839D01*
X156898Y-228209D01*
X156585Y-227474D01*
X156428Y-226634D01*
Y-225794D01*
X156585Y-224954D01*
X156898Y-224219D01*
X157368Y-223589D01*
X157916Y-223169D01*
X158543Y-223064D01*
X159170Y-223169D01*
X159718Y-223589D01*
X160188Y-224219D01*
X160501Y-224954D01*
X160658Y-225794D01*
Y-226634D01*
X160501Y-227474D01*
X160188Y-228209D01*
X159718Y-228839D01*
X159170Y-229259D01*
X158543Y-229364D01*
G01X171143D02*
Y-226529D01*
X169576Y-223064D01*
G01X172710D02*
X171143Y-226529D01*
G01X175720Y-223064D02*
Y-227579D01*
X176033Y-228524D01*
X176660Y-229154D01*
X177443Y-229364D01*
X178226Y-229154D01*
X178853Y-228524D01*
X179166Y-227579D01*
Y-223064D01*
G01X181785Y-229364D02*
X183743Y-223064D01*
X185701Y-229364D01*
G01X184996Y-227159D02*
X182490D01*
G01X188241Y-229364D02*
Y-223064D01*
X191845Y-229364D01*
Y-223064D01*
G01X37041Y-219364D02*
Y-213064D01*
X40645Y-219364D01*
Y-213064D01*
G01X45143Y-219364D02*
X44516Y-219259D01*
X43968Y-218839D01*
X43498Y-218209D01*
X43185Y-217474D01*
X43028Y-216634D01*
Y-215794D01*
X43185Y-214954D01*
X43498Y-214219D01*
X43968Y-213589D01*
X44516Y-213169D01*
X45143Y-213064D01*
X45770Y-213169D01*
X46318Y-213589D01*
X46788Y-214219D01*
X47101Y-214954D01*
X47258Y-215794D01*
Y-216634D01*
X47101Y-217474D01*
X46788Y-218209D01*
X46318Y-218839D01*
X45770Y-219259D01*
X45143Y-219364D01*
G01X51443Y-219574D02*
X51286Y-219469D01*
Y-219259D01*
X51443Y-219154D01*
X51600Y-219259D01*
Y-219469D01*
X51443Y-219574D01*
G01X57743Y-219364D02*
Y-213064D01*
X56803Y-214324D01*
G01Y-219364D02*
X58683D01*
G01X64043D02*
X64591Y-219259D01*
X65218Y-218944D01*
X65610Y-218419D01*
X65766Y-217684D01*
X65610Y-216949D01*
X65140Y-216319D01*
X64435Y-216004D01*
X63651D01*
X63181Y-215794D01*
X62790Y-215269D01*
X62633Y-214534D01*
X62868Y-213799D01*
X63416Y-213274D01*
X64043Y-213064D01*
X64670Y-213274D01*
X65218Y-213799D01*
X65453Y-214534D01*
X65296Y-215269D01*
X64905Y-215794D01*
X64435Y-216004D01*
X63651D01*
X62946Y-216319D01*
X62476Y-216949D01*
X62320Y-217684D01*
X62476Y-218419D01*
X62868Y-218944D01*
X63495Y-219259D01*
X64043Y-219364D01*
G01X70343D02*
X70891Y-219259D01*
X71518Y-218944D01*
X71910Y-218419D01*
X72066Y-217684D01*
X71910Y-216949D01*
X71440Y-216319D01*
X70735Y-216004D01*
X69951D01*
X69481Y-215794D01*
X69090Y-215269D01*
X68933Y-214534D01*
X69168Y-213799D01*
X69716Y-213274D01*
X70343Y-213064D01*
X70970Y-213274D01*
X71518Y-213799D01*
X71753Y-214534D01*
X71596Y-215269D01*
X71205Y-215794D01*
X70735Y-216004D01*
X69951D01*
X69246Y-216319D01*
X68776Y-216949D01*
X68620Y-217684D01*
X68776Y-218419D01*
X69168Y-218944D01*
X69795Y-219259D01*
X70343Y-219364D01*
G01X76486Y-220519D02*
X76800Y-219154D01*
G01X80593Y-213064D02*
X81690Y-219364D01*
X82943Y-213064D01*
X84196Y-219364D01*
X85293Y-213064D01*
G01X90810Y-219364D02*
X87676D01*
Y-213064D01*
X90810D01*
G01X89556Y-216109D02*
X87676D01*
G01X93741Y-219364D02*
Y-213064D01*
X97345Y-219364D01*
Y-213064D01*
G01X106498Y-219364D02*
Y-213064D01*
G01X109788D02*
Y-219364D01*
G01Y-216214D02*
X106498D01*
G01X112093Y-213064D02*
X113190Y-219364D01*
X114443Y-213064D01*
X115696Y-219364D01*
X116793Y-213064D01*
G01X118785Y-219364D02*
X120743Y-213064D01*
X122701Y-219364D01*
G01X121996Y-217159D02*
X119490D01*
G01X131855Y-214114D02*
X132325Y-213484D01*
X132873Y-213169D01*
X133500Y-213064D01*
X134283Y-213274D01*
X134831Y-213799D01*
X134988Y-214429D01*
X134910Y-215059D01*
X134596Y-215584D01*
X133030Y-216634D01*
X132325Y-217369D01*
X131855Y-218419D01*
X131698Y-219364D01*
X134988D01*
G01X137841D02*
Y-213064D01*
X141445Y-219364D01*
Y-213064D01*
G01X144220Y-219364D02*
Y-213064D01*
X145786D01*
X146413Y-213379D01*
X146883Y-213799D01*
X147275Y-214429D01*
X147588Y-215164D01*
X147666Y-216214D01*
X147588Y-217264D01*
X147275Y-217999D01*
X146883Y-218629D01*
X146413Y-219049D01*
X145786Y-219364D01*
X144220D01*
G01X156976D02*
Y-213064D01*
X158935D01*
X159561Y-213379D01*
X159953Y-213799D01*
X160110Y-214639D01*
X159953Y-215479D01*
X159483Y-216004D01*
X158935Y-216319D01*
X156976D01*
G01X158935D02*
X160110Y-219364D01*
G01X163120D02*
Y-213064D01*
X164686D01*
X165313Y-213379D01*
X165783Y-213799D01*
X166175Y-214429D01*
X166488Y-215164D01*
X166566Y-216214D01*
X166488Y-217264D01*
X166175Y-217999D01*
X165783Y-218629D01*
X165313Y-219049D01*
X164686Y-219364D01*
X163120D01*
G01X171143Y-219574D02*
X170986Y-219469D01*
Y-219259D01*
X171143Y-219154D01*
X171300Y-219259D01*
Y-219469D01*
X171143Y-219574D01*
G01X61143Y-206664D02*
X58623Y-206247D01*
X56418Y-204581D01*
X54528Y-202081D01*
X53268Y-199164D01*
X52638Y-195831D01*
Y-192497D01*
X53268Y-189164D01*
X54528Y-186247D01*
X56418Y-183748D01*
X58623Y-182081D01*
X61143Y-181664D01*
X63663Y-182081D01*
X65868Y-183748D01*
X67758Y-186247D01*
X69018Y-189164D01*
X69648Y-192497D01*
Y-195831D01*
X69018Y-199164D01*
X67758Y-202081D01*
X65868Y-204581D01*
X63663Y-206247D01*
X61143Y-206664D01*
G01X63663Y-199997D02*
X67443Y-206664D01*
G01X80988Y-189998D02*
Y-201664D01*
X82248Y-204581D01*
X84138Y-206247D01*
X86343Y-206664D01*
X88548Y-206247D01*
X90438Y-204581D01*
X91698Y-201664D01*
G01Y-206664D02*
Y-189998D01*
G01X117213Y-206664D02*
Y-189998D01*
G01Y-192914D02*
X115953Y-191248D01*
X114063Y-190414D01*
X111858Y-189998D01*
X109653Y-190831D01*
X107763Y-192497D01*
X106503Y-194998D01*
X105873Y-198331D01*
X106503Y-201664D01*
X107763Y-204165D01*
X109653Y-205831D01*
X111858Y-206664D01*
X114063Y-206247D01*
X115953Y-204998D01*
X117213Y-203331D01*
G01X131388Y-206664D02*
Y-189998D01*
G01Y-194164D02*
X132648Y-192081D01*
X134538Y-190414D01*
X137058Y-189998D01*
X139263Y-190414D01*
X141153Y-192081D01*
X142098Y-194998D01*
Y-206664D01*
G01X161943Y-181664D02*
Y-206664D01*
G01X157533Y-189998D02*
X166353D01*
G01X192813Y-206664D02*
Y-189998D01*
G01Y-192914D02*
X191553Y-191248D01*
X189663Y-190414D01*
X187458Y-189998D01*
X185253Y-190831D01*
X183363Y-192497D01*
X182103Y-194998D01*
X181473Y-198331D01*
X182103Y-201664D01*
X183363Y-204165D01*
X185253Y-205831D01*
X187458Y-206664D01*
X189663Y-206247D01*
X191553Y-204998D01*
X192813Y-203331D01*
G01X232493Y-186364D02*
Y-194364D01*
X236493D01*
G01X244293D02*
Y-189031D01*
G01Y-189964D02*
X243893Y-189431D01*
X243293Y-189164D01*
X242593Y-189031D01*
X241893Y-189297D01*
X241293Y-189831D01*
X240893Y-190631D01*
X240693Y-191697D01*
X240893Y-192764D01*
X241293Y-193564D01*
X241893Y-194097D01*
X242593Y-194364D01*
X243293Y-194231D01*
X243893Y-193831D01*
X244293Y-193298D01*
G01X248393Y-196764D02*
X248993Y-197031D01*
X249793Y-196764D01*
X250293Y-196231D01*
X250693Y-195564D01*
X251293Y-193431D01*
X252593Y-189031D01*
G01X249393D02*
X251293Y-193431D01*
G01X256993Y-190764D02*
X260193D01*
X259893Y-189831D01*
X259393Y-189297D01*
X258693Y-189031D01*
X257993Y-189164D01*
X257393Y-189564D01*
X256993Y-190497D01*
X256793Y-191298D01*
Y-192097D01*
X256993Y-192897D01*
X257493Y-193697D01*
X258093Y-194231D01*
X258793Y-194364D01*
X259493Y-194097D01*
X260193Y-193298D01*
G01X265093Y-194364D02*
Y-189031D01*
G01Y-190097D02*
X265593Y-189564D01*
X266093Y-189164D01*
X266793Y-189031D01*
X267293Y-189164D01*
X267893Y-189564D01*
G01X254793Y-236364D02*
X257193D01*
G01X255993D02*
Y-244364D01*
G01X254793D02*
X257193D01*
G01X262593D02*
Y-239031D01*
G01Y-240097D02*
X263093Y-239564D01*
X263593Y-239164D01*
X264293Y-239031D01*
X264793Y-239164D01*
X265393Y-239564D01*
G01X270493Y-240764D02*
X273693D01*
X273393Y-239831D01*
X272893Y-239297D01*
X272193Y-239031D01*
X271493Y-239164D01*
X270893Y-239564D01*
X270493Y-240497D01*
X270293Y-241298D01*
Y-242097D01*
X270493Y-242897D01*
X270993Y-243697D01*
X271593Y-244231D01*
X272293Y-244364D01*
X272993Y-244097D01*
X273693Y-243298D01*
G01X278293Y-244364D02*
Y-239031D01*
G01Y-240364D02*
X278693Y-239697D01*
X279293Y-239164D01*
X280093Y-239031D01*
X280793Y-239164D01*
X281393Y-239697D01*
X281693Y-240631D01*
Y-244364D01*
G01X286493Y-240764D02*
X289693D01*
X289393Y-239831D01*
X288893Y-239297D01*
X288193Y-239031D01*
X287493Y-239164D01*
X286893Y-239564D01*
X286493Y-240497D01*
X286293Y-241298D01*
Y-242097D01*
X286493Y-242897D01*
X286993Y-243697D01*
X287593Y-244231D01*
X288293Y-244364D01*
X288993Y-244097D01*
X289693Y-243298D01*
G01X259729Y-212806D02*
X261729D01*
Y-215206D01*
X261129Y-216006D01*
X260429Y-216539D01*
X259429Y-216806D01*
X258429Y-216539D01*
X257729Y-216006D01*
X257129Y-215206D01*
X256729Y-214273D01*
X256529Y-213206D01*
Y-212273D01*
X256729Y-211473D01*
X257129Y-210539D01*
X257729Y-209739D01*
X258329Y-209206D01*
X259129Y-208806D01*
X259829D01*
X260629Y-209073D01*
X261229Y-209606D01*
G01X264829Y-216806D02*
Y-208806D01*
X269429Y-216806D01*
Y-208806D01*
G01X272929Y-216806D02*
Y-208806D01*
X274929D01*
X275729Y-209206D01*
X276329Y-209739D01*
X276829Y-210539D01*
X277229Y-211473D01*
X277329Y-212806D01*
X277229Y-214139D01*
X276829Y-215073D01*
X276329Y-215873D01*
X275729Y-216406D01*
X274929Y-216806D01*
X272929D01*
G01X280929Y-215206D02*
X281529Y-216139D01*
X282329Y-216673D01*
X283229Y-216806D01*
X284029Y-216673D01*
X284829Y-216006D01*
X285329Y-215206D01*
X285429Y-214406D01*
X285229Y-213473D01*
X284529Y-212806D01*
X283829Y-212539D01*
X282929D01*
G01X283829D02*
X284429Y-212139D01*
X284929Y-211473D01*
X285129Y-210673D01*
X284929Y-209873D01*
X284429Y-209206D01*
X283529Y-208806D01*
X282629Y-208939D01*
X281729Y-209473D01*
G01X279138Y-194382D02*
X279838Y-195048D01*
X280638Y-195315D01*
X281438Y-195048D01*
X282138Y-194249D01*
X282638Y-193048D01*
X282838Y-191848D01*
Y-190382D01*
X282638Y-189182D01*
X282138Y-188115D01*
X281538Y-187582D01*
X280838Y-187315D01*
X280038Y-187582D01*
X279438Y-188115D01*
X279038Y-188915D01*
X278838Y-189982D01*
X279038Y-190915D01*
X279538Y-191848D01*
X280138Y-192382D01*
X280838Y-192515D01*
X281638Y-192249D01*
X282238Y-191582D01*
X282838Y-190382D01*
G01X359093Y-237697D02*
X359693Y-236897D01*
X360393Y-236497D01*
X361193Y-236364D01*
X362193Y-236631D01*
X362893Y-237297D01*
X363093Y-238097D01*
X362993Y-238898D01*
X362593Y-239564D01*
X360593Y-240897D01*
X359693Y-241831D01*
X359093Y-243164D01*
X358893Y-244364D01*
X363093D01*
G01X368993Y-236364D02*
X368193Y-236631D01*
X367593Y-237297D01*
X367193Y-238097D01*
X366893Y-239164D01*
X366793Y-240364D01*
X366893Y-241564D01*
X367193Y-242631D01*
X367593Y-243431D01*
X368193Y-244097D01*
X368993Y-244364D01*
X369793Y-244097D01*
X370393Y-243431D01*
X370793Y-242631D01*
X371093Y-241564D01*
X371193Y-240364D01*
X371093Y-239164D01*
X370793Y-238097D01*
X370393Y-237297D01*
X369793Y-236631D01*
X368993Y-236364D01*
G01X376993Y-244364D02*
Y-236364D01*
X375793Y-237964D01*
G01Y-244364D02*
X378193D01*
G01X383093Y-237697D02*
X383693Y-236897D01*
X384393Y-236497D01*
X385193Y-236364D01*
X386193Y-236631D01*
X386893Y-237297D01*
X387093Y-238097D01*
X386993Y-238898D01*
X386593Y-239564D01*
X384593Y-240897D01*
X383693Y-241831D01*
X383093Y-243164D01*
X382893Y-244364D01*
X387093D01*
G01X391193Y-244631D02*
X394793Y-236364D01*
G01X400993Y-244364D02*
Y-236364D01*
X399793Y-237964D01*
G01Y-244364D02*
X402193D01*
G01X408993Y-236364D02*
X408193Y-236631D01*
X407593Y-237297D01*
X407193Y-238097D01*
X406893Y-239164D01*
X406793Y-240364D01*
X406893Y-241564D01*
X407193Y-242631D01*
X407593Y-243431D01*
X408193Y-244097D01*
X408993Y-244364D01*
X409793Y-244097D01*
X410393Y-243431D01*
X410793Y-242631D01*
X411093Y-241564D01*
X411193Y-240364D01*
X411093Y-239164D01*
X410793Y-238097D01*
X410393Y-237297D01*
X409793Y-236631D01*
X408993Y-236364D01*
G01X415193Y-244631D02*
X418793Y-236364D01*
G01X422793Y-242764D02*
X423393Y-243697D01*
X424193Y-244231D01*
X425093Y-244364D01*
X425893Y-244231D01*
X426693Y-243564D01*
X427193Y-242764D01*
X427293Y-241964D01*
X427093Y-241031D01*
X426393Y-240364D01*
X425693Y-240097D01*
X424793D01*
G01X425693D02*
X426293Y-239697D01*
X426793Y-239031D01*
X426993Y-238231D01*
X426793Y-237431D01*
X426293Y-236764D01*
X425393Y-236364D01*
X424493Y-236497D01*
X423593Y-237031D01*
G01X432993Y-244364D02*
Y-236364D01*
X431793Y-237964D01*
G01Y-244364D02*
X434193D01*
G01X358793Y-219364D02*
Y-211364D01*
X360793D01*
X361593Y-211764D01*
X362193Y-212297D01*
X362693Y-213097D01*
X363093Y-214031D01*
X363193Y-215364D01*
X363093Y-216697D01*
X362693Y-217631D01*
X362193Y-218431D01*
X361593Y-218964D01*
X360793Y-219364D01*
X358793D01*
G01X366493D02*
X368993Y-211364D01*
X371493Y-219364D01*
G01X370593Y-216564D02*
X367393D01*
G01X376993Y-211364D02*
Y-219364D01*
G01X374693Y-211364D02*
X379293D01*
G01X383093Y-216031D02*
X383793Y-215097D01*
X384393Y-214564D01*
X385193Y-214297D01*
X385893Y-214564D01*
X386393Y-215097D01*
X386793Y-215897D01*
X386893Y-216831D01*
X386793Y-217631D01*
X386393Y-218431D01*
X385793Y-219097D01*
X385093Y-219364D01*
X384293Y-219097D01*
X383593Y-218298D01*
X383193Y-217097D01*
X383093Y-215764D01*
X383293Y-214031D01*
X383593Y-213097D01*
X384093Y-212164D01*
X384793Y-211497D01*
X385493Y-211364D01*
X386193Y-211631D01*
X386693Y-212297D01*
G01X390393Y-219364D02*
Y-211364D01*
X392993Y-218031D01*
X395593Y-211364D01*
Y-219364D01*
G01X400993Y-211364D02*
Y-219364D01*
G01X398693Y-211364D02*
X403293D01*
G01X406893Y-219364D02*
Y-211364D01*
G01X411093D02*
Y-219364D01*
G01Y-215364D02*
X406893D01*
G01X414793Y-217764D02*
X415393Y-218697D01*
X416193Y-219231D01*
X417093Y-219364D01*
X417893Y-219231D01*
X418693Y-218564D01*
X419193Y-217764D01*
X419293Y-216964D01*
X419093Y-216031D01*
X418393Y-215364D01*
X417693Y-215097D01*
X416793D01*
G01X417693D02*
X418293Y-214697D01*
X418793Y-214031D01*
X418993Y-213231D01*
X418793Y-212431D01*
X418293Y-211764D01*
X417393Y-211364D01*
X416493Y-211497D01*
X415593Y-212031D01*
G01X422493Y-219364D02*
X424993Y-211364D01*
X427493Y-219364D01*
G01X426593Y-216564D02*
X423393D01*
G01X430793Y-219364D02*
Y-211364D01*
X432793D01*
X433593Y-211764D01*
X434193Y-212297D01*
X434693Y-213097D01*
X435093Y-214031D01*
X435193Y-215364D01*
X435093Y-216697D01*
X434693Y-217631D01*
X434193Y-218431D01*
X433593Y-218964D01*
X432793Y-219364D01*
X430793D01*
G01X440993Y-211364D02*
X440193Y-211631D01*
X439593Y-212297D01*
X439193Y-213097D01*
X438893Y-214164D01*
X438793Y-215364D01*
X438893Y-216564D01*
X439193Y-217631D01*
X439593Y-218431D01*
X440193Y-219097D01*
X440993Y-219364D01*
X441793Y-219097D01*
X442393Y-218431D01*
X442793Y-217631D01*
X443093Y-216564D01*
X443193Y-215364D01*
X443093Y-214164D01*
X442793Y-213097D01*
X442393Y-212297D01*
X441793Y-211631D01*
X440993Y-211364D01*
G01X380993Y-186364D02*
Y-194364D01*
G01X378693Y-186364D02*
X383293D01*
G01X387093Y-191031D02*
X387793Y-190097D01*
X388393Y-189564D01*
X389193Y-189297D01*
X389893Y-189564D01*
X390393Y-190097D01*
X390793Y-190897D01*
X390893Y-191831D01*
X390793Y-192631D01*
X390393Y-193431D01*
X389793Y-194097D01*
X389093Y-194364D01*
X388293Y-194097D01*
X387593Y-193298D01*
X387193Y-192097D01*
X387093Y-190764D01*
X387293Y-189031D01*
X387593Y-188097D01*
X388093Y-187164D01*
X388793Y-186497D01*
X389493Y-186364D01*
X390193Y-186631D01*
X390693Y-187297D01*
G01X394393Y-194364D02*
Y-186364D01*
X396993Y-193031D01*
X399593Y-186364D01*
Y-194364D01*
G01X401993Y-197031D02*
X407993D01*
G01X415193Y-187031D02*
X414593Y-186631D01*
X413893Y-186364D01*
X413093D01*
X412193Y-186764D01*
X411493Y-187431D01*
X410993Y-188231D01*
X410593Y-189564D01*
X410493Y-190764D01*
X410693Y-191964D01*
X410993Y-192764D01*
X411593Y-193564D01*
X412293Y-194097D01*
X412993Y-194364D01*
X413693D01*
X414393Y-194097D01*
X414993Y-193697D01*
X415493Y-193164D01*
G01X418393Y-194364D02*
Y-186364D01*
X420993Y-193031D01*
X423593Y-186364D01*
Y-194364D01*
G01X425993Y-197031D02*
X431993D01*
G01X434793Y-194364D02*
Y-186364D01*
X436793D01*
X437593Y-186764D01*
X438193Y-187297D01*
X438693Y-188097D01*
X439093Y-189031D01*
X439193Y-190364D01*
X439093Y-191697D01*
X438693Y-192631D01*
X438193Y-193431D01*
X437593Y-193964D01*
X436793Y-194364D01*
X434793D01*
G01X473793Y-244364D02*
Y-236364D01*
X475793D01*
X476593Y-236764D01*
X477193Y-237297D01*
X477693Y-238097D01*
X478093Y-239031D01*
X478193Y-240364D01*
X478093Y-241697D01*
X477693Y-242631D01*
X477193Y-243431D01*
X476593Y-243964D01*
X475793Y-244364D01*
X473793D01*
G01X503493D02*
Y-236364D01*
X502293Y-237964D01*
G01Y-244364D02*
X504693D01*
G01X509593Y-241031D02*
X510293Y-240097D01*
X510893Y-239564D01*
X511693Y-239297D01*
X512393Y-239564D01*
X512893Y-240097D01*
X513293Y-240897D01*
X513393Y-241831D01*
X513293Y-242631D01*
X512893Y-243431D01*
X512293Y-244097D01*
X511593Y-244364D01*
X510793Y-244097D01*
X510093Y-243298D01*
X509693Y-242097D01*
X509593Y-240764D01*
X509793Y-239031D01*
X510093Y-238097D01*
X510593Y-237164D01*
X511293Y-236497D01*
X511993Y-236364D01*
X512693Y-236631D01*
X513193Y-237297D01*
M02*
